G04 ================== begin FILE IDENTIFICATION RECORD ==================*
G04 Layout Name:  D:/<user>/Wistron_project/16342-2/gbr/16342-2.brd*
G04 Film Name:    DP_REF_L1*
G04 File Format:  Gerber RS274X*
G04 File Origin:  Cadence Allegro 16.5-S056*
G04 Origin Date:  Mon Aug 07 11:25:00 2017*
G04 *
G04 Layer:  BOARD GEOMETRY/DP_REF_L1_TBL*
G04 Layer:  BOARD GEOMETRY/DP_REF_L1_TOP*
G04 Layer:  BOARD GEOMETRY/PANEL_OUTLINE*
G04 *
G04 Offset:    (0.00 0.00)*
G04 Mirror:    No*
G04 Mode:      Positive*
G04 Rotation:  0*
G04 FullContactRelief:  No*
G04 UndefLineWidth:     6.00*
G04 ================== end FILE IDENTIFICATION RECORD ====================*
%FSLAX35Y35*MOIN*%
%IR0*IPPOS*OFA0.00000B0.00000*MIA0B0*SFA1.00000B1.00000*%
%ADD10C,.02*%
%ADD11C,.006*%
%ADD12C,.0049*%
%ADD13C,.00575*%
G75*
%LPD*%
G75*
G54D10*
G01X975497Y625480D02*
X1727997D01*
G01X975497Y729430D02*
Y625480D01*
G01Y694780D02*
X1727997D01*
G01X975497Y660130D02*
X1727997D01*
G01X975497Y729430D02*
X1727997D01*
G01X1150497D02*
Y625480D01*
G01X1412997Y729430D02*
Y625480D01*
G01X1517997Y729430D02*
Y625480D01*
G01X1727997Y729430D02*
Y625480D01*
G54D11*
G01X6250Y-32800D02*
Y-50300D01*
G01X1228Y-32800D02*
X11272D01*
G01X20038Y-50300D02*
Y-32800D01*
G01Y-41258D02*
X21130Y-39800D01*
X22222Y-38925D01*
X23968Y-38634D01*
X25278Y-38925D01*
X26807Y-40092D01*
X27462Y-41842D01*
Y-50300D01*
G01X41250Y-38634D02*
Y-50300D01*
G01Y-33967D02*
X40813Y-33675D01*
Y-33092D01*
X41250Y-32800D01*
X41687Y-33092D01*
Y-33675D01*
X41250Y-33967D01*
G01X55475Y-48259D02*
X56567Y-49425D01*
X58095Y-50300D01*
X59405D01*
X60715Y-49717D01*
X61588Y-48842D01*
X62025Y-47676D01*
X61807Y-45925D01*
X60933Y-45050D01*
X57003Y-43300D01*
X56130Y-41258D01*
X56567Y-39800D01*
X57440Y-38925D01*
X58750Y-38634D01*
X60060Y-38925D01*
X61370Y-39800D01*
G01X90693Y-54675D02*
X92222Y-55842D01*
X93968Y-56133D01*
X95496Y-55842D01*
X96807Y-54384D01*
X97680Y-52342D01*
Y-38634D01*
G01Y-40967D02*
X96807Y-39800D01*
X95496Y-38925D01*
X93968Y-38634D01*
X92222Y-39217D01*
X91130Y-40383D01*
X90256Y-42425D01*
X89820Y-44467D01*
X90038Y-46217D01*
X90912Y-48259D01*
X92222Y-49717D01*
X93968Y-50300D01*
X95278Y-50008D01*
X96807Y-48842D01*
X97680Y-47676D01*
G01X107975Y-42425D02*
X114962D01*
X114307Y-40383D01*
X113215Y-39217D01*
X111687Y-38634D01*
X110158Y-38925D01*
X108848Y-39800D01*
X107975Y-41842D01*
X107538Y-43592D01*
Y-45342D01*
X107975Y-47092D01*
X109067Y-48842D01*
X110377Y-50008D01*
X111905Y-50300D01*
X113433Y-49717D01*
X114962Y-47967D01*
G01X125693Y-50300D02*
Y-38634D01*
G01Y-40967D02*
X126785Y-39800D01*
X127877Y-38925D01*
X129405Y-38634D01*
X130496Y-38925D01*
X131807Y-39800D01*
G01X142320Y-50300D02*
Y-32800D01*
G01Y-41550D02*
X143412Y-39800D01*
X144722Y-38925D01*
X146032Y-38634D01*
X147996Y-39217D01*
X149307Y-40383D01*
X150180Y-42425D01*
Y-44758D01*
X149743Y-47092D01*
X148870Y-48842D01*
X147342Y-50008D01*
X146032Y-50300D01*
X144722Y-50008D01*
X143412Y-49134D01*
X142320Y-47676D01*
G01X160475Y-42425D02*
X167462D01*
X166807Y-40383D01*
X165715Y-39217D01*
X164187Y-38634D01*
X162658Y-38925D01*
X161348Y-39800D01*
X160475Y-41842D01*
X160038Y-43592D01*
Y-45342D01*
X160475Y-47092D01*
X161567Y-48842D01*
X162877Y-50008D01*
X164405Y-50300D01*
X165933Y-49717D01*
X167462Y-47967D01*
G01X178193Y-50300D02*
Y-38634D01*
G01Y-40967D02*
X179285Y-39800D01*
X180377Y-38925D01*
X181905Y-38634D01*
X182996Y-38925D01*
X184307Y-39800D01*
G01X216250Y-38634D02*
Y-50300D01*
G01Y-33967D02*
X215813Y-33675D01*
Y-33092D01*
X216250Y-32800D01*
X216687Y-33092D01*
Y-33675D01*
X216250Y-33967D01*
G01X230475Y-48259D02*
X231567Y-49425D01*
X233095Y-50300D01*
X234405D01*
X235715Y-49717D01*
X236588Y-48842D01*
X237025Y-47676D01*
X236807Y-45925D01*
X235933Y-45050D01*
X232003Y-43300D01*
X231130Y-41258D01*
X231567Y-39800D01*
X232440Y-38925D01*
X233750Y-38634D01*
X235060Y-38925D01*
X236370Y-39800D01*
G01X265256Y-54675D02*
X266785Y-55842D01*
X268095Y-56133D01*
X269842Y-55550D01*
X271152Y-54092D01*
X271807Y-51466D01*
Y-38634D01*
G01Y-33967D02*
X271370Y-33675D01*
Y-33092D01*
X271807Y-32800D01*
X272243Y-33092D01*
Y-33675D01*
X271807Y-33967D01*
G01X282538Y-38634D02*
Y-46800D01*
X283412Y-48842D01*
X284722Y-50008D01*
X286250Y-50300D01*
X287778Y-50008D01*
X289088Y-48842D01*
X289962Y-46800D01*
G01Y-50300D02*
Y-38634D01*
G01X300475Y-48259D02*
X301567Y-49425D01*
X303095Y-50300D01*
X304405D01*
X305715Y-49717D01*
X306588Y-48842D01*
X307025Y-47676D01*
X306807Y-45925D01*
X305933Y-45050D01*
X302003Y-43300D01*
X301130Y-41258D01*
X301567Y-39800D01*
X302440Y-38925D01*
X303750Y-38634D01*
X305060Y-38925D01*
X306370Y-39800D01*
G01X321250Y-32800D02*
Y-50300D01*
G01X318193Y-38634D02*
X324307D01*
G01X354940Y-50300D02*
Y-35425D01*
X355377Y-33967D01*
X356250Y-33092D01*
X357560Y-32800D01*
X358870Y-33383D01*
X359525Y-34842D01*
G01X356905Y-39800D02*
X352538D01*
G01X373750Y-50300D02*
X372440Y-50008D01*
X371130Y-48842D01*
X370256Y-46800D01*
X369820Y-44467D01*
X370256Y-42133D01*
X371130Y-40092D01*
X372440Y-38925D01*
X373750Y-38634D01*
X375060Y-38925D01*
X376370Y-40092D01*
X377243Y-42133D01*
X377462Y-44467D01*
X377243Y-46800D01*
X376370Y-48842D01*
X375060Y-50008D01*
X373750Y-50300D01*
G01X388193D02*
Y-38634D01*
G01Y-40967D02*
X389285Y-39800D01*
X390377Y-38925D01*
X391905Y-38634D01*
X392996Y-38925D01*
X394307Y-39800D01*
G01X421665Y-55550D02*
X422975Y-56133D01*
X424722Y-55550D01*
X425813Y-54384D01*
X426687Y-52925D01*
X427996Y-48259D01*
X430835Y-38634D01*
G01X423848D02*
X427996Y-48259D01*
G01X443750Y-50300D02*
X442440Y-50008D01*
X441130Y-48842D01*
X440256Y-46800D01*
X439820Y-44467D01*
X440256Y-42133D01*
X441130Y-40092D01*
X442440Y-38925D01*
X443750Y-38634D01*
X445060Y-38925D01*
X446370Y-40092D01*
X447243Y-42133D01*
X447462Y-44467D01*
X447243Y-46800D01*
X446370Y-48842D01*
X445060Y-50008D01*
X443750Y-50300D01*
G01X457538Y-38634D02*
Y-46800D01*
X458412Y-48842D01*
X459722Y-50008D01*
X461250Y-50300D01*
X462778Y-50008D01*
X464088Y-48842D01*
X464962Y-46800D01*
G01Y-50300D02*
Y-38634D01*
G01X475693Y-50300D02*
Y-38634D01*
G01Y-40967D02*
X476785Y-39800D01*
X477877Y-38925D01*
X479405Y-38634D01*
X480496Y-38925D01*
X481807Y-39800D01*
G01X510693Y-50300D02*
Y-38634D01*
G01Y-40967D02*
X511785Y-39800D01*
X512877Y-38925D01*
X514405Y-38634D01*
X515496Y-38925D01*
X516807Y-39800D01*
G01X527975Y-42425D02*
X534962D01*
X534307Y-40383D01*
X533215Y-39217D01*
X531687Y-38634D01*
X530158Y-38925D01*
X528848Y-39800D01*
X527975Y-41842D01*
X527538Y-43592D01*
Y-45342D01*
X527975Y-47092D01*
X529067Y-48842D01*
X530377Y-50008D01*
X531905Y-50300D01*
X533433Y-49717D01*
X534962Y-47967D01*
G01X547440Y-50300D02*
Y-35425D01*
X547877Y-33967D01*
X548750Y-33092D01*
X550060Y-32800D01*
X551370Y-33383D01*
X552025Y-34842D01*
G01X549405Y-39800D02*
X545038D01*
G01X562975Y-42425D02*
X569962D01*
X569307Y-40383D01*
X568215Y-39217D01*
X566687Y-38634D01*
X565158Y-38925D01*
X563848Y-39800D01*
X562975Y-41842D01*
X562538Y-43592D01*
Y-45342D01*
X562975Y-47092D01*
X564067Y-48842D01*
X565377Y-50008D01*
X566905Y-50300D01*
X568433Y-49717D01*
X569962Y-47967D01*
G01X580693Y-50300D02*
Y-38634D01*
G01Y-40967D02*
X581785Y-39800D01*
X582877Y-38925D01*
X584405Y-38634D01*
X585496Y-38925D01*
X586807Y-39800D01*
G01X597975Y-42425D02*
X604962D01*
X604307Y-40383D01*
X603215Y-39217D01*
X601687Y-38634D01*
X600158Y-38925D01*
X598848Y-39800D01*
X597975Y-41842D01*
X597538Y-43592D01*
Y-45342D01*
X597975Y-47092D01*
X599067Y-48842D01*
X600377Y-50008D01*
X601905Y-50300D01*
X603433Y-49717D01*
X604962Y-47967D01*
G01X615038Y-50300D02*
Y-38634D01*
G01Y-41550D02*
X615912Y-40092D01*
X617222Y-38925D01*
X618968Y-38634D01*
X620496Y-38925D01*
X621807Y-40092D01*
X622462Y-42133D01*
Y-50300D01*
G01X639743Y-40092D02*
X638215Y-38925D01*
X636905Y-38634D01*
X635158Y-39217D01*
X633848Y-40383D01*
X632975Y-42425D01*
X632756Y-44467D01*
X632975Y-46509D01*
X633848Y-48259D01*
X635158Y-49717D01*
X636905Y-50300D01*
X638433Y-49717D01*
X639743Y-48550D01*
G01X650475Y-42425D02*
X657462D01*
X656807Y-40383D01*
X655715Y-39217D01*
X654187Y-38634D01*
X652658Y-38925D01*
X651348Y-39800D01*
X650475Y-41842D01*
X650038Y-43592D01*
Y-45342D01*
X650475Y-47092D01*
X651567Y-48842D01*
X652877Y-50008D01*
X654405Y-50300D01*
X655933Y-49717D01*
X657462Y-47967D01*
G01X688750Y-32800D02*
Y-50300D01*
G01X685693Y-38634D02*
X691807D01*
G01X706250Y-50300D02*
X704940Y-50008D01*
X703630Y-48842D01*
X702756Y-46800D01*
X702320Y-44467D01*
X702756Y-42133D01*
X703630Y-40092D01*
X704940Y-38925D01*
X706250Y-38634D01*
X707560Y-38925D01*
X708870Y-40092D01*
X709743Y-42133D01*
X709962Y-44467D01*
X709743Y-46800D01*
X708870Y-48842D01*
X707560Y-50008D01*
X706250Y-50300D01*
G01X739940D02*
Y-35425D01*
X740377Y-33967D01*
X741250Y-33092D01*
X742560Y-32800D01*
X743870Y-33383D01*
X744525Y-34842D01*
G01X741905Y-39800D02*
X737538D01*
G01X758750Y-38634D02*
Y-50300D01*
G01Y-33967D02*
X758313Y-33675D01*
Y-33092D01*
X758750Y-32800D01*
X759187Y-33092D01*
Y-33675D01*
X758750Y-33967D01*
G01X772538Y-50300D02*
Y-38634D01*
G01Y-41550D02*
X773412Y-40092D01*
X774722Y-38925D01*
X776468Y-38634D01*
X777996Y-38925D01*
X779307Y-40092D01*
X779962Y-42133D01*
Y-50300D01*
G01X797680Y-32800D02*
Y-50300D01*
G01Y-47676D02*
X796807Y-49134D01*
X795496Y-50008D01*
X793968Y-50300D01*
X792222Y-49717D01*
X790912Y-48259D01*
X790038Y-46509D01*
X789820Y-44467D01*
X790038Y-42425D01*
X790912Y-40675D01*
X792222Y-39217D01*
X793968Y-38634D01*
X795496Y-38925D01*
X796588Y-39509D01*
X797680Y-40675D01*
G01X828750Y-32800D02*
Y-50300D01*
G01X825693Y-38634D02*
X831807D01*
G01X842538Y-50300D02*
Y-32800D01*
G01Y-41258D02*
X843630Y-39800D01*
X844722Y-38925D01*
X846468Y-38634D01*
X847778Y-38925D01*
X849307Y-40092D01*
X849962Y-41842D01*
Y-50300D01*
G01X860475Y-42425D02*
X867462D01*
X866807Y-40383D01*
X865715Y-39217D01*
X864187Y-38634D01*
X862658Y-38925D01*
X861348Y-39800D01*
X860475Y-41842D01*
X860038Y-43592D01*
Y-45342D01*
X860475Y-47092D01*
X861567Y-48842D01*
X862877Y-50008D01*
X864405Y-50300D01*
X865933Y-49717D01*
X867462Y-47967D01*
G01X893947Y-50300D02*
Y-32800D01*
X898313D01*
X900060Y-33675D01*
X901370Y-34842D01*
X902462Y-36591D01*
X903335Y-38634D01*
X903553Y-41550D01*
X903335Y-44467D01*
X902462Y-46509D01*
X901370Y-48259D01*
X900060Y-49425D01*
X898313Y-50300D01*
X893947D01*
G01X911883D02*
Y-32800D01*
X917123D01*
X918870Y-33675D01*
X920180Y-35717D01*
X920617Y-38050D01*
X920180Y-40383D01*
X919088Y-42133D01*
X917123Y-43009D01*
X911883D01*
G01X951250Y-38634D02*
Y-50300D01*
G01Y-33967D02*
X950813Y-33675D01*
Y-33092D01*
X951250Y-32800D01*
X951687Y-33092D01*
Y-33675D01*
X951250Y-33967D01*
G01X962200Y-50300D02*
Y-38634D01*
G01Y-41842D02*
X962855Y-40383D01*
X963947Y-39217D01*
X965475Y-38634D01*
X967003Y-39217D01*
X968095Y-40383D01*
X968750Y-41842D01*
Y-50300D01*
G01Y-41842D02*
X969405Y-40383D01*
X970496Y-39217D01*
X972025Y-38634D01*
X973553Y-39217D01*
X974645Y-40383D01*
X975300Y-42133D01*
Y-50300D01*
G01X982320Y-56133D02*
Y-38634D01*
G01Y-41258D02*
X983412Y-39800D01*
X984503Y-38925D01*
X986250Y-38634D01*
X987778Y-38925D01*
X989307Y-40383D01*
X989962Y-42425D01*
X990180Y-44467D01*
X989962Y-46509D01*
X989307Y-48550D01*
X987996Y-49717D01*
X986250Y-50300D01*
X984722Y-50008D01*
X983193Y-49134D01*
X982320Y-47967D01*
G01X1000475Y-42425D02*
X1007462D01*
X1006807Y-40383D01*
X1005715Y-39217D01*
X1004187Y-38634D01*
X1002658Y-38925D01*
X1001348Y-39800D01*
X1000475Y-41842D01*
X1000038Y-43592D01*
Y-45342D01*
X1000475Y-47092D01*
X1001567Y-48842D01*
X1002877Y-50008D01*
X1004405Y-50300D01*
X1005933Y-49717D01*
X1007462Y-47967D01*
G01X1025180Y-32800D02*
Y-50300D01*
G01Y-47676D02*
X1024307Y-49134D01*
X1022996Y-50008D01*
X1021468Y-50300D01*
X1019722Y-49717D01*
X1018412Y-48259D01*
X1017538Y-46509D01*
X1017320Y-44467D01*
X1017538Y-42425D01*
X1018412Y-40675D01*
X1019722Y-39217D01*
X1021468Y-38634D01*
X1022996Y-38925D01*
X1024088Y-39509D01*
X1025180Y-40675D01*
G01X1042680Y-50300D02*
Y-38634D01*
G01Y-40675D02*
X1041807Y-39509D01*
X1040496Y-38925D01*
X1038968Y-38634D01*
X1037440Y-39217D01*
X1036130Y-40383D01*
X1035256Y-42133D01*
X1034820Y-44467D01*
X1035256Y-46800D01*
X1036130Y-48550D01*
X1037440Y-49717D01*
X1038968Y-50300D01*
X1040496Y-50008D01*
X1041807Y-49134D01*
X1042680Y-47967D01*
G01X1052538Y-50300D02*
Y-38634D01*
G01Y-41550D02*
X1053412Y-40092D01*
X1054722Y-38925D01*
X1056468Y-38634D01*
X1057996Y-38925D01*
X1059307Y-40092D01*
X1059962Y-42133D01*
Y-50300D01*
G01X1077243Y-40092D02*
X1075715Y-38925D01*
X1074405Y-38634D01*
X1072658Y-39217D01*
X1071348Y-40383D01*
X1070475Y-42425D01*
X1070256Y-44467D01*
X1070475Y-46509D01*
X1071348Y-48259D01*
X1072658Y-49717D01*
X1074405Y-50300D01*
X1075933Y-49717D01*
X1077243Y-48550D01*
G01X1087975Y-42425D02*
X1094962D01*
X1094307Y-40383D01*
X1093215Y-39217D01*
X1091687Y-38634D01*
X1090158Y-38925D01*
X1088848Y-39800D01*
X1087975Y-41842D01*
X1087538Y-43592D01*
Y-45342D01*
X1087975Y-47092D01*
X1089067Y-48842D01*
X1090377Y-50008D01*
X1091905Y-50300D01*
X1093433Y-49717D01*
X1094962Y-47967D01*
G01X1126250Y-32800D02*
Y-50300D01*
G01X1123193Y-38634D02*
X1129307D01*
G01X1140693Y-50300D02*
Y-38634D01*
G01Y-40967D02*
X1141785Y-39800D01*
X1142877Y-38925D01*
X1144405Y-38634D01*
X1145496Y-38925D01*
X1146807Y-39800D01*
G01X1165180Y-50300D02*
Y-38634D01*
G01Y-40675D02*
X1164307Y-39509D01*
X1162996Y-38925D01*
X1161468Y-38634D01*
X1159940Y-39217D01*
X1158630Y-40383D01*
X1157756Y-42133D01*
X1157320Y-44467D01*
X1157756Y-46800D01*
X1158630Y-48550D01*
X1159940Y-49717D01*
X1161468Y-50300D01*
X1162996Y-50008D01*
X1164307Y-49134D01*
X1165180Y-47967D01*
G01X1182243Y-40092D02*
X1180715Y-38925D01*
X1179405Y-38634D01*
X1177658Y-39217D01*
X1176348Y-40383D01*
X1175475Y-42425D01*
X1175256Y-44467D01*
X1175475Y-46509D01*
X1176348Y-48259D01*
X1177658Y-49717D01*
X1179405Y-50300D01*
X1180933Y-49717D01*
X1182243Y-48550D01*
G01X1192975Y-42425D02*
X1199962D01*
X1199307Y-40383D01*
X1198215Y-39217D01*
X1196687Y-38634D01*
X1195158Y-38925D01*
X1193848Y-39800D01*
X1192975Y-41842D01*
X1192538Y-43592D01*
Y-45342D01*
X1192975Y-47092D01*
X1194067Y-48842D01*
X1195377Y-50008D01*
X1196905Y-50300D01*
X1198433Y-49717D01*
X1199962Y-47967D01*
G01X1210475Y-48259D02*
X1211567Y-49425D01*
X1213095Y-50300D01*
X1214405D01*
X1215715Y-49717D01*
X1216588Y-48842D01*
X1217025Y-47676D01*
X1216807Y-45925D01*
X1215933Y-45050D01*
X1212003Y-43300D01*
X1211130Y-41258D01*
X1211567Y-39800D01*
X1212440Y-38925D01*
X1213750Y-38634D01*
X1215060Y-38925D01*
X1216370Y-39800D01*
G01X1248750Y-38634D02*
Y-50300D01*
G01Y-33967D02*
X1248313Y-33675D01*
Y-33092D01*
X1248750Y-32800D01*
X1249187Y-33092D01*
Y-33675D01*
X1248750Y-33967D01*
G01X1262538Y-50300D02*
Y-38634D01*
G01Y-41550D02*
X1263412Y-40092D01*
X1264722Y-38925D01*
X1266468Y-38634D01*
X1267996Y-38925D01*
X1269307Y-40092D01*
X1269962Y-42133D01*
Y-50300D01*
G01X1301250D02*
Y-32800D01*
G01X1322680Y-50300D02*
Y-38634D01*
G01Y-40675D02*
X1321807Y-39509D01*
X1320496Y-38925D01*
X1318968Y-38634D01*
X1317440Y-39217D01*
X1316130Y-40383D01*
X1315256Y-42133D01*
X1314820Y-44467D01*
X1315256Y-46800D01*
X1316130Y-48550D01*
X1317440Y-49717D01*
X1318968Y-50300D01*
X1320496Y-50008D01*
X1321807Y-49134D01*
X1322680Y-47967D01*
G01X1331665Y-55550D02*
X1332975Y-56133D01*
X1334722Y-55550D01*
X1335813Y-54384D01*
X1336687Y-52925D01*
X1337996Y-48259D01*
X1340835Y-38634D01*
G01X1333848D02*
X1337996Y-48259D01*
G01X1350475Y-42425D02*
X1357462D01*
X1356807Y-40383D01*
X1355715Y-39217D01*
X1354187Y-38634D01*
X1352658Y-38925D01*
X1351348Y-39800D01*
X1350475Y-41842D01*
X1350038Y-43592D01*
Y-45342D01*
X1350475Y-47092D01*
X1351567Y-48842D01*
X1352877Y-50008D01*
X1354405Y-50300D01*
X1355933Y-49717D01*
X1357462Y-47967D01*
G01X1368193Y-50300D02*
Y-38634D01*
G01Y-40967D02*
X1369285Y-39800D01*
X1370377Y-38925D01*
X1371905Y-38634D01*
X1372996Y-38925D01*
X1374307Y-39800D01*
G01X1401883Y-32800D02*
Y-50300D01*
X1410617D01*
G01X1423750D02*
Y-32800D01*
X1421130Y-36300D01*
G01Y-50300D02*
X1426370D01*
G01X1441250Y-50883D02*
X1440813Y-50592D01*
Y-50008D01*
X1441250Y-49717D01*
X1441687Y-50008D01*
Y-50592D01*
X1441250Y-50883D01*
G01X999127Y722030D02*
X1004367D01*
G01X1001747D02*
Y704530D01*
G01X999127D02*
X1004367D01*
G01X1013570D02*
Y722030D01*
X1019247Y707447D01*
X1024924Y722030D01*
Y704530D01*
G01X1032380D02*
Y722030D01*
X1037620D01*
X1039367Y721155D01*
X1040677Y719113D01*
X1041114Y716780D01*
X1040677Y714447D01*
X1039585Y712697D01*
X1037620Y711821D01*
X1032380D01*
G01X1053155Y698697D02*
X1050972Y701613D01*
X1049880Y704530D01*
Y716196D01*
X1050972Y719113D01*
X1053155Y722030D01*
G01X1071747Y704530D02*
X1070000Y704822D01*
X1068472Y705988D01*
X1067162Y707738D01*
X1066288Y709780D01*
X1065852Y712113D01*
Y714447D01*
X1066288Y716780D01*
X1067162Y718822D01*
X1068472Y720571D01*
X1070000Y721738D01*
X1071747Y722030D01*
X1073493Y721738D01*
X1075022Y720571D01*
X1076332Y718822D01*
X1077206Y716780D01*
X1077642Y714447D01*
Y712113D01*
X1077206Y709780D01*
X1076332Y707738D01*
X1075022Y705988D01*
X1073493Y704822D01*
X1071747Y704530D01*
G01X1085535D02*
Y722030D01*
G01Y713572D02*
X1086627Y715030D01*
X1087719Y715905D01*
X1089465Y716196D01*
X1090775Y715905D01*
X1092304Y714738D01*
X1092959Y712988D01*
Y704530D01*
G01X1100197D02*
Y716196D01*
G01Y712988D02*
X1100852Y714447D01*
X1101944Y715613D01*
X1103472Y716196D01*
X1105000Y715613D01*
X1106092Y714447D01*
X1106747Y712988D01*
Y704530D01*
G01Y712988D02*
X1107402Y714447D01*
X1108493Y715613D01*
X1110022Y716196D01*
X1111550Y715613D01*
X1112642Y714447D01*
X1113297Y712697D01*
Y704530D01*
G01X1125339Y698697D02*
X1127522Y701613D01*
X1128614Y704530D01*
Y716196D01*
X1127522Y719113D01*
X1125339Y722030D01*
G01X977244Y739180D02*
Y756680D01*
X981610D01*
X983357Y755805D01*
X984667Y754638D01*
X985759Y752889D01*
X986632Y750846D01*
X986850Y747930D01*
X986632Y745013D01*
X985759Y742971D01*
X984667Y741221D01*
X983357Y740055D01*
X981610Y739180D01*
X977244D01*
G01X995180D02*
Y756680D01*
X1000420D01*
X1002167Y755805D01*
X1003477Y753763D01*
X1003914Y751430D01*
X1003477Y749097D01*
X1002385Y747347D01*
X1000420Y746471D01*
X995180D01*
G01X1031927Y756680D02*
X1037167D01*
G01X1034547D02*
Y739180D01*
G01X1031927D02*
X1037167D01*
G01X1046370D02*
Y756680D01*
X1052047Y742097D01*
X1057724Y756680D01*
Y739180D01*
G01X1065180D02*
Y756680D01*
X1070420D01*
X1072167Y755805D01*
X1073477Y753763D01*
X1073914Y751430D01*
X1073477Y749097D01*
X1072385Y747347D01*
X1070420Y746471D01*
X1065180D01*
G01X1091414Y739180D02*
X1082680D01*
Y756680D01*
X1091414D01*
G01X1087920Y748222D02*
X1082680D01*
G01X1099744Y739180D02*
Y756680D01*
X1104110D01*
X1105857Y755805D01*
X1107167Y754638D01*
X1108259Y752889D01*
X1109132Y750846D01*
X1109350Y747930D01*
X1109132Y745013D01*
X1108259Y742971D01*
X1107167Y741221D01*
X1105857Y740055D01*
X1104110Y739180D01*
X1099744D01*
G01X1116588D02*
X1122047Y756680D01*
X1127506Y739180D01*
G01X1125540Y745305D02*
X1118553D01*
G01X1134525Y739180D02*
Y756680D01*
X1144569Y739180D01*
Y756680D01*
G01X1161850Y755221D02*
X1160540Y756097D01*
X1159012Y756680D01*
X1157265D01*
X1155300Y755805D01*
X1153772Y754347D01*
X1152680Y752596D01*
X1151807Y749680D01*
X1151588Y747055D01*
X1152025Y744430D01*
X1152680Y742680D01*
X1153990Y740930D01*
X1155519Y739763D01*
X1157047Y739180D01*
X1158575D01*
X1160104Y739763D01*
X1161414Y740638D01*
X1162506Y741804D01*
G01X1178914Y739180D02*
X1170180D01*
Y756680D01*
X1178914D01*
G01X1175420Y748222D02*
X1170180D01*
G01X1209547Y756680D02*
Y739180D01*
G01X1204525Y756680D02*
X1214569D01*
G01X1221588Y739180D02*
X1227047Y756680D01*
X1232506Y739180D01*
G01X1230540Y745305D02*
X1223553D01*
G01X1246293Y748513D02*
X1247167Y749388D01*
X1247822Y750846D01*
X1248259Y752889D01*
X1247822Y754638D01*
X1246949Y755805D01*
X1245420Y756680D01*
X1239525D01*
Y739180D01*
X1246730D01*
X1248259Y740346D01*
X1249132Y742097D01*
X1249569Y744138D01*
X1249132Y746180D01*
X1247822Y747930D01*
X1246293Y748513D01*
X1239525D01*
G01X1257680Y756680D02*
Y739180D01*
X1266414D01*
G01X1283914D02*
X1275180D01*
Y756680D01*
X1283914D01*
G01X1280420Y748222D02*
X1275180D01*
G01X1297047Y738597D02*
X1296610Y738888D01*
Y739472D01*
X1297047Y739763D01*
X1297484Y739472D01*
Y738888D01*
X1297047Y738597D01*
G01Y746471D02*
X1296610Y746763D01*
Y747347D01*
X1297047Y747638D01*
X1297484Y747347D01*
Y746763D01*
X1297047Y746471D01*
G01X1327680Y756680D02*
Y739180D01*
X1336414D01*
G01X1349547D02*
Y756680D01*
X1346927Y753180D01*
G01Y739180D02*
X1352167D01*
G01X1027997Y635230D02*
Y652730D01*
X1025377Y649230D01*
G01Y635230D02*
X1030617D01*
G01X1045497Y652730D02*
X1043750Y652147D01*
X1042440Y650688D01*
X1041567Y648939D01*
X1040912Y646605D01*
X1040694Y643980D01*
X1040912Y641355D01*
X1041567Y639021D01*
X1042440Y637271D01*
X1043750Y635813D01*
X1045497Y635230D01*
X1047243Y635813D01*
X1048554Y637271D01*
X1049427Y639021D01*
X1050082Y641355D01*
X1050300Y643980D01*
X1050082Y646605D01*
X1049427Y648939D01*
X1048554Y650688D01*
X1047243Y652147D01*
X1045497Y652730D01*
G01X1062997D02*
X1061250Y652147D01*
X1059940Y650688D01*
X1059067Y648939D01*
X1058412Y646605D01*
X1058194Y643980D01*
X1058412Y641355D01*
X1059067Y639021D01*
X1059940Y637271D01*
X1061250Y635813D01*
X1062997Y635230D01*
X1064743Y635813D01*
X1066054Y637271D01*
X1066927Y639021D01*
X1067582Y641355D01*
X1067800Y643980D01*
X1067582Y646605D01*
X1066927Y648939D01*
X1066054Y650688D01*
X1064743Y652147D01*
X1062997Y652730D01*
G01X1080497Y634647D02*
X1080060Y634938D01*
Y635522D01*
X1080497Y635813D01*
X1080934Y635522D01*
Y634938D01*
X1080497Y634647D01*
G01X1097997Y652730D02*
X1096250Y652147D01*
X1094940Y650688D01*
X1094067Y648939D01*
X1093412Y646605D01*
X1093194Y643980D01*
X1093412Y641355D01*
X1094067Y639021D01*
X1094940Y637271D01*
X1096250Y635813D01*
X1097997Y635230D01*
X1099743Y635813D01*
X1101054Y637271D01*
X1101927Y639021D01*
X1102582Y641355D01*
X1102800Y643980D01*
X1102582Y646605D01*
X1101927Y648939D01*
X1101054Y650688D01*
X1099743Y652147D01*
X1097997Y652730D01*
G01X1036747Y669880D02*
X1038275Y670172D01*
X1040022Y671046D01*
X1041114Y672504D01*
X1041550Y674547D01*
X1041114Y676588D01*
X1039804Y678338D01*
X1037839Y679213D01*
X1035655D01*
X1034345Y679797D01*
X1033253Y681255D01*
X1032817Y683296D01*
X1033472Y685338D01*
X1035000Y686797D01*
X1036747Y687380D01*
X1038493Y686797D01*
X1040022Y685338D01*
X1040677Y683296D01*
X1040240Y681255D01*
X1039149Y679797D01*
X1037839Y679213D01*
X1035655D01*
X1033690Y678338D01*
X1032380Y676588D01*
X1031944Y674547D01*
X1032380Y672504D01*
X1033472Y671046D01*
X1035219Y670172D01*
X1036747Y669880D01*
G01X1049444Y672504D02*
X1050753Y671046D01*
X1052282Y670172D01*
X1054247Y669880D01*
X1056212Y670463D01*
X1057740Y671630D01*
X1058832Y673671D01*
X1059050Y676005D01*
X1058614Y678338D01*
X1057522Y679797D01*
X1055993Y680963D01*
X1054465Y681255D01*
X1052937Y680963D01*
X1050972Y679797D01*
X1051627Y687380D01*
X1057522D01*
G01X1071747Y669297D02*
X1071310Y669588D01*
Y670172D01*
X1071747Y670463D01*
X1072184Y670172D01*
Y669588D01*
X1071747Y669297D01*
G01X1089247Y687380D02*
X1087500Y686797D01*
X1086190Y685338D01*
X1085317Y683589D01*
X1084662Y681255D01*
X1084444Y678630D01*
X1084662Y676005D01*
X1085317Y673671D01*
X1086190Y671921D01*
X1087500Y670463D01*
X1089247Y669880D01*
X1090993Y670463D01*
X1092304Y671921D01*
X1093177Y673671D01*
X1093832Y676005D01*
X1094050Y678630D01*
X1093832Y681255D01*
X1093177Y683589D01*
X1092304Y685338D01*
X1090993Y686797D01*
X1089247Y687380D01*
G01X1223117Y635230D02*
Y652730D01*
X1215038Y640188D01*
X1225956D01*
G01X1237997Y634647D02*
X1237560Y634938D01*
Y635522D01*
X1237997Y635813D01*
X1238434Y635522D01*
Y634938D01*
X1237997Y634647D01*
G01X1251785Y637271D02*
X1253314Y635813D01*
X1255060Y635230D01*
X1256807Y635813D01*
X1258335Y637563D01*
X1259427Y640188D01*
X1259864Y642813D01*
Y646021D01*
X1259427Y648646D01*
X1258335Y650980D01*
X1257025Y652147D01*
X1255497Y652730D01*
X1253750Y652147D01*
X1252440Y650980D01*
X1251567Y649230D01*
X1251130Y646896D01*
X1251567Y644855D01*
X1252659Y642813D01*
X1253969Y641646D01*
X1255497Y641355D01*
X1257243Y641938D01*
X1258554Y643397D01*
X1259864Y646021D01*
G01X1269067Y634647D02*
X1276927Y652730D01*
G01X1290497Y635230D02*
Y652730D01*
X1287877Y649230D01*
G01Y635230D02*
X1293117D01*
G01X1307997D02*
Y652730D01*
X1305377Y649230D01*
G01Y635230D02*
X1310617D01*
G01X1325497Y634647D02*
X1325060Y634938D01*
Y635522D01*
X1325497Y635813D01*
X1325934Y635522D01*
Y634938D01*
X1325497Y634647D01*
G01X1342997Y635230D02*
Y652730D01*
X1340377Y649230D01*
G01Y635230D02*
X1345617D01*
G01X1187697Y722030D02*
X1190753Y704530D01*
X1194247Y722030D01*
X1197740Y704530D01*
X1200797Y722030D01*
G01X1209127D02*
X1214367D01*
G01X1211747D02*
Y704530D01*
G01X1209127D02*
X1214367D01*
G01X1224444D02*
Y722030D01*
X1228810D01*
X1230557Y721155D01*
X1231867Y719988D01*
X1232959Y718239D01*
X1233832Y716196D01*
X1234050Y713280D01*
X1233832Y710363D01*
X1232959Y708321D01*
X1231867Y706571D01*
X1230557Y705405D01*
X1228810Y704530D01*
X1224444D01*
G01X1246747Y722030D02*
Y704530D01*
G01X1241725Y722030D02*
X1251769D01*
G01X1259662Y704530D02*
Y722030D01*
G01X1268832D02*
Y704530D01*
G01Y713280D02*
X1259662D01*
G01X1280655Y698697D02*
X1278472Y701613D01*
X1277380Y704530D01*
Y716196D01*
X1278472Y719113D01*
X1280655Y722030D01*
G01X1292697Y704530D02*
Y716196D01*
G01Y712988D02*
X1293352Y714447D01*
X1294444Y715613D01*
X1295972Y716196D01*
X1297500Y715613D01*
X1298592Y714447D01*
X1299247Y712988D01*
Y704530D01*
G01Y712988D02*
X1299902Y714447D01*
X1300993Y715613D01*
X1302522Y716196D01*
X1304050Y715613D01*
X1305142Y714447D01*
X1305797Y712697D01*
Y704530D01*
G01X1316747Y716196D02*
Y704530D01*
G01Y720863D02*
X1316310Y721155D01*
Y721738D01*
X1316747Y722030D01*
X1317184Y721738D01*
Y721155D01*
X1316747Y720863D01*
G01X1334247Y704530D02*
Y722030D01*
G01X1348472Y706571D02*
X1349564Y705405D01*
X1351092Y704530D01*
X1352402D01*
X1353712Y705113D01*
X1354585Y705988D01*
X1355022Y707154D01*
X1354804Y708905D01*
X1353930Y709780D01*
X1350000Y711530D01*
X1349127Y713572D01*
X1349564Y715030D01*
X1350437Y715905D01*
X1351747Y716196D01*
X1353057Y715905D01*
X1354367Y715030D01*
G01X1370339Y698697D02*
X1372522Y701613D01*
X1373614Y704530D01*
Y716196D01*
X1372522Y719113D01*
X1370339Y722030D01*
G01X1215694Y672504D02*
X1217003Y671046D01*
X1218532Y670172D01*
X1220497Y669880D01*
X1222462Y670463D01*
X1223990Y671630D01*
X1225082Y673671D01*
X1225300Y676005D01*
X1224864Y678338D01*
X1223772Y679797D01*
X1222243Y680963D01*
X1220715Y681255D01*
X1219187Y680963D01*
X1217222Y679797D01*
X1217877Y687380D01*
X1223772D01*
G01X1237997Y669297D02*
X1237560Y669588D01*
Y670172D01*
X1237997Y670463D01*
X1238434Y670172D01*
Y669588D01*
X1237997Y669297D01*
G01X1255060Y669880D02*
X1255497Y673671D01*
X1256152Y676880D01*
X1257025Y679797D01*
X1258117Y683005D01*
X1259864Y687380D01*
X1251130D01*
G01X1268194Y672504D02*
X1269503Y671046D01*
X1271032Y670172D01*
X1272997Y669880D01*
X1274962Y670463D01*
X1276490Y671630D01*
X1277582Y673671D01*
X1277800Y676005D01*
X1277364Y678338D01*
X1276272Y679797D01*
X1274743Y680963D01*
X1273215Y681255D01*
X1271687Y680963D01*
X1269722Y679797D01*
X1270377Y687380D01*
X1276272D01*
G01X1286567Y669297D02*
X1294427Y687380D01*
G01X1303849Y677171D02*
X1305377Y679213D01*
X1306687Y680380D01*
X1308434Y680963D01*
X1309962Y680380D01*
X1311054Y679213D01*
X1311927Y677463D01*
X1312145Y675422D01*
X1311927Y673671D01*
X1311054Y671921D01*
X1309743Y670463D01*
X1308215Y669880D01*
X1306469Y670463D01*
X1304940Y672213D01*
X1304067Y674838D01*
X1303849Y677755D01*
X1304285Y681546D01*
X1304940Y683589D01*
X1306032Y685630D01*
X1307560Y687088D01*
X1309089Y687380D01*
X1310617Y686797D01*
X1311709Y685338D01*
G01X1325497Y669297D02*
X1325060Y669588D01*
Y670172D01*
X1325497Y670463D01*
X1325934Y670172D01*
Y669588D01*
X1325497Y669297D01*
G01X1338194Y672504D02*
X1339503Y671046D01*
X1341032Y670172D01*
X1342997Y669880D01*
X1344962Y670463D01*
X1346490Y671630D01*
X1347582Y673671D01*
X1347800Y676005D01*
X1347364Y678338D01*
X1346272Y679797D01*
X1344743Y680963D01*
X1343215Y681255D01*
X1341687Y680963D01*
X1339722Y679797D01*
X1340377Y687380D01*
X1346272D01*
G01X1451944Y635230D02*
Y652730D01*
X1456310D01*
X1458057Y651855D01*
X1459367Y650688D01*
X1460459Y648939D01*
X1461332Y646896D01*
X1461550Y643980D01*
X1461332Y641063D01*
X1460459Y639021D01*
X1459367Y637271D01*
X1458057Y636105D01*
X1456310Y635230D01*
X1451944D01*
G01X1469880D02*
Y652730D01*
X1475120D01*
X1476867Y651855D01*
X1478177Y649813D01*
X1478614Y647480D01*
X1478177Y645147D01*
X1477085Y643397D01*
X1475120Y642521D01*
X1469880D01*
G01X1439247Y722030D02*
Y704530D01*
G01X1434225Y722030D02*
X1444269D01*
G01X1456747Y704530D02*
Y712405D01*
X1452380Y722030D01*
G01X1461114D02*
X1456747Y712405D01*
G01X1469880Y704530D02*
Y722030D01*
X1475120D01*
X1476867Y721155D01*
X1478177Y719113D01*
X1478614Y716780D01*
X1478177Y714447D01*
X1477085Y712697D01*
X1475120Y711821D01*
X1469880D01*
G01X1496114Y704530D02*
X1487380D01*
Y722030D01*
X1496114D01*
G01X1492620Y713572D02*
X1487380D01*
G01X1451944Y669880D02*
Y687380D01*
X1456310D01*
X1458057Y686505D01*
X1459367Y685338D01*
X1460459Y683589D01*
X1461332Y681546D01*
X1461550Y678630D01*
X1461332Y675713D01*
X1460459Y673671D01*
X1459367Y671921D01*
X1458057Y670755D01*
X1456310Y669880D01*
X1451944D01*
G01X1469880D02*
Y687380D01*
X1475120D01*
X1476867Y686505D01*
X1478177Y684463D01*
X1478614Y682130D01*
X1478177Y679797D01*
X1477085Y678047D01*
X1475120Y677171D01*
X1469880D01*
G01X1539880Y704530D02*
Y722030D01*
X1545339D01*
X1547085Y721155D01*
X1548177Y719988D01*
X1548614Y717655D01*
X1548177Y715321D01*
X1546867Y713863D01*
X1545339Y712988D01*
X1539880D01*
G01X1545339D02*
X1548614Y704530D01*
G01X1558472Y712405D02*
X1565459D01*
X1564804Y714447D01*
X1563712Y715613D01*
X1562184Y716196D01*
X1560655Y715905D01*
X1559345Y715030D01*
X1558472Y712988D01*
X1558035Y711238D01*
Y709488D01*
X1558472Y707738D01*
X1559564Y705988D01*
X1560874Y704822D01*
X1562402Y704530D01*
X1563930Y705113D01*
X1565459Y706863D01*
G01X1577937Y704530D02*
Y719405D01*
X1578374Y720863D01*
X1579247Y721738D01*
X1580557Y722030D01*
X1581867Y721447D01*
X1582522Y719988D01*
G01X1579902Y715030D02*
X1575535D01*
G01X1596747Y703947D02*
X1596310Y704238D01*
Y704822D01*
X1596747Y705113D01*
X1597184Y704822D01*
Y704238D01*
X1596747Y703947D01*
G01X1627380Y704530D02*
Y722030D01*
X1632620D01*
X1634367Y721155D01*
X1635677Y719113D01*
X1636114Y716780D01*
X1635677Y714447D01*
X1634585Y712697D01*
X1632620Y711821D01*
X1627380D01*
G01X1649247Y704530D02*
Y722030D01*
G01X1670677Y704530D02*
Y716196D01*
G01Y714155D02*
X1669804Y715321D01*
X1668493Y715905D01*
X1666965Y716196D01*
X1665437Y715613D01*
X1664127Y714447D01*
X1663253Y712697D01*
X1662817Y710363D01*
X1663253Y708030D01*
X1664127Y706280D01*
X1665437Y705113D01*
X1666965Y704530D01*
X1668493Y704822D01*
X1669804Y705696D01*
X1670677Y706863D01*
G01X1680535Y704530D02*
Y716196D01*
G01Y713280D02*
X1681409Y714738D01*
X1682719Y715905D01*
X1684465Y716196D01*
X1685993Y715905D01*
X1687304Y714738D01*
X1687959Y712697D01*
Y704530D01*
G01X1698472Y712405D02*
X1705459D01*
X1704804Y714447D01*
X1703712Y715613D01*
X1702184Y716196D01*
X1700655Y715905D01*
X1699345Y715030D01*
X1698472Y712988D01*
X1698035Y711238D01*
Y709488D01*
X1698472Y707738D01*
X1699564Y705988D01*
X1700874Y704822D01*
X1702402Y704530D01*
X1703930Y705113D01*
X1705459Y706863D01*
G01X1609880Y652730D02*
Y635230D01*
X1618614D01*
G01X1627599Y649813D02*
X1628909Y651563D01*
X1630437Y652438D01*
X1632184Y652730D01*
X1634367Y652147D01*
X1635895Y650688D01*
X1636332Y648939D01*
X1636114Y647188D01*
X1635240Y645730D01*
X1630874Y642813D01*
X1628909Y640772D01*
X1627599Y637854D01*
X1627162Y635230D01*
X1636332D01*
G01X1609880Y687380D02*
Y669880D01*
X1618614D01*
G01X1627599Y684463D02*
X1628909Y686213D01*
X1630437Y687088D01*
X1632184Y687380D01*
X1634367Y686797D01*
X1635895Y685338D01*
X1636332Y683589D01*
X1636114Y681838D01*
X1635240Y680380D01*
X1630874Y677463D01*
X1628909Y675422D01*
X1627599Y672504D01*
X1627162Y669880D01*
X1636332D01*
G01X1744744Y703947D02*
X1754350Y716780D01*
G01X1749547Y719113D02*
Y701613D01*
G01X1754350Y703947D02*
X1744744Y716780D01*
G01X1742997Y710363D02*
X1756097D01*
G01X1781709D02*
X1787385D01*
G01X1814744Y704530D02*
Y722030D01*
X1819110D01*
X1820857Y721155D01*
X1822167Y719988D01*
X1823259Y718239D01*
X1824132Y716196D01*
X1824350Y713280D01*
X1824132Y710363D01*
X1823259Y708321D01*
X1822167Y706571D01*
X1820857Y705405D01*
X1819110Y704530D01*
X1814744D01*
G01X1833772Y712405D02*
X1840759D01*
X1840104Y714447D01*
X1839012Y715613D01*
X1837484Y716196D01*
X1835955Y715905D01*
X1834645Y715030D01*
X1833772Y712988D01*
X1833335Y711238D01*
Y709488D01*
X1833772Y707738D01*
X1834864Y705988D01*
X1836174Y704822D01*
X1837702Y704530D01*
X1839230Y705113D01*
X1840759Y706863D01*
G01X1850835Y704530D02*
Y716196D01*
G01Y713280D02*
X1851709Y714738D01*
X1853019Y715905D01*
X1854765Y716196D01*
X1856293Y715905D01*
X1857604Y714738D01*
X1858259Y712697D01*
Y704530D01*
G01X1872047D02*
X1870737Y704822D01*
X1869427Y705988D01*
X1868553Y708030D01*
X1868117Y710363D01*
X1868553Y712697D01*
X1869427Y714738D01*
X1870737Y715905D01*
X1872047Y716196D01*
X1873357Y715905D01*
X1874667Y714738D01*
X1875540Y712697D01*
X1875759Y710363D01*
X1875540Y708030D01*
X1874667Y705988D01*
X1873357Y704822D01*
X1872047Y704530D01*
G01X1889547Y722030D02*
Y704530D01*
G01X1886490Y716196D02*
X1892604D01*
G01X1903772Y712405D02*
X1910759D01*
X1910104Y714447D01*
X1909012Y715613D01*
X1907484Y716196D01*
X1905955Y715905D01*
X1904645Y715030D01*
X1903772Y712988D01*
X1903335Y711238D01*
Y709488D01*
X1903772Y707738D01*
X1904864Y705988D01*
X1906174Y704822D01*
X1907702Y704530D01*
X1909230Y705113D01*
X1910759Y706863D01*
G01X1921272Y706571D02*
X1922364Y705405D01*
X1923892Y704530D01*
X1925202D01*
X1926512Y705113D01*
X1927385Y705988D01*
X1927822Y707154D01*
X1927604Y708905D01*
X1926730Y709780D01*
X1922800Y711530D01*
X1921927Y713572D01*
X1922364Y715030D01*
X1923237Y715905D01*
X1924547Y716196D01*
X1925857Y715905D01*
X1927167Y715030D01*
G01X1959547Y722030D02*
Y704530D01*
G01X1956490Y716196D02*
X1962604D01*
G01X1973335Y704530D02*
Y722030D01*
G01Y713572D02*
X1974427Y715030D01*
X1975519Y715905D01*
X1977265Y716196D01*
X1978575Y715905D01*
X1980104Y714738D01*
X1980759Y712988D01*
Y704530D01*
G01X1998477D02*
Y716196D01*
G01Y714155D02*
X1997604Y715321D01*
X1996293Y715905D01*
X1994765Y716196D01*
X1993237Y715613D01*
X1991927Y714447D01*
X1991053Y712697D01*
X1990617Y710363D01*
X1991053Y708030D01*
X1991927Y706280D01*
X1993237Y705113D01*
X1994765Y704530D01*
X1996293Y704822D01*
X1997604Y705696D01*
X1998477Y706863D01*
G01X2012047Y722030D02*
Y704530D01*
G01X2008990Y716196D02*
X2015104D01*
G01X2047047Y722030D02*
Y704530D01*
G01X2043990Y716196D02*
X2050104D01*
G01X2060835Y704530D02*
Y722030D01*
G01Y713572D02*
X2061927Y715030D01*
X2063019Y715905D01*
X2064765Y716196D01*
X2066075Y715905D01*
X2067604Y714738D01*
X2068259Y712988D01*
Y704530D01*
G01X2082047Y716196D02*
Y704530D01*
G01Y720863D02*
X2081610Y721155D01*
Y721738D01*
X2082047Y722030D01*
X2082484Y721738D01*
Y721155D01*
X2082047Y720863D01*
G01X2096272Y706571D02*
X2097364Y705405D01*
X2098892Y704530D01*
X2100202D01*
X2101512Y705113D01*
X2102385Y705988D01*
X2102822Y707154D01*
X2102604Y708905D01*
X2101730Y709780D01*
X2097800Y711530D01*
X2096927Y713572D01*
X2097364Y715030D01*
X2098237Y715905D01*
X2099547Y716196D01*
X2100857Y715905D01*
X2102167Y715030D01*
G01X2131927Y722030D02*
X2137167D01*
G01X2134547D02*
Y704530D01*
G01X2131927D02*
X2137167D01*
G01X2145497D02*
Y716196D01*
G01Y712988D02*
X2146152Y714447D01*
X2147244Y715613D01*
X2148772Y716196D01*
X2150300Y715613D01*
X2151392Y714447D01*
X2152047Y712988D01*
Y704530D01*
G01Y712988D02*
X2152702Y714447D01*
X2153793Y715613D01*
X2155322Y716196D01*
X2156850Y715613D01*
X2157942Y714447D01*
X2158597Y712697D01*
Y704530D01*
G01X2165617Y698697D02*
Y716196D01*
G01Y713572D02*
X2166709Y715030D01*
X2167800Y715905D01*
X2169547Y716196D01*
X2171075Y715905D01*
X2172604Y714447D01*
X2173259Y712405D01*
X2173477Y710363D01*
X2173259Y708321D01*
X2172604Y706280D01*
X2171293Y705113D01*
X2169547Y704530D01*
X2168019Y704822D01*
X2166490Y705696D01*
X2165617Y706863D01*
G01X2183772Y712405D02*
X2190759D01*
X2190104Y714447D01*
X2189012Y715613D01*
X2187484Y716196D01*
X2185955Y715905D01*
X2184645Y715030D01*
X2183772Y712988D01*
X2183335Y711238D01*
Y709488D01*
X2183772Y707738D01*
X2184864Y705988D01*
X2186174Y704822D01*
X2187702Y704530D01*
X2189230Y705113D01*
X2190759Y706863D01*
G01X2208477Y722030D02*
Y704530D01*
G01Y707154D02*
X2207604Y705696D01*
X2206293Y704822D01*
X2204765Y704530D01*
X2203019Y705113D01*
X2201709Y706571D01*
X2200835Y708321D01*
X2200617Y710363D01*
X2200835Y712405D01*
X2201709Y714155D01*
X2203019Y715613D01*
X2204765Y716196D01*
X2206293Y715905D01*
X2207385Y715321D01*
X2208477Y714155D01*
G01X2225977Y704530D02*
Y716196D01*
G01Y714155D02*
X2225104Y715321D01*
X2223793Y715905D01*
X2222265Y716196D01*
X2220737Y715613D01*
X2219427Y714447D01*
X2218553Y712697D01*
X2218117Y710363D01*
X2218553Y708030D01*
X2219427Y706280D01*
X2220737Y705113D01*
X2222265Y704530D01*
X2223793Y704822D01*
X2225104Y705696D01*
X2225977Y706863D01*
G01X2235835Y704530D02*
Y716196D01*
G01Y713280D02*
X2236709Y714738D01*
X2238019Y715905D01*
X2239765Y716196D01*
X2241293Y715905D01*
X2242604Y714738D01*
X2243259Y712697D01*
Y704530D01*
G01X2260540Y714738D02*
X2259012Y715905D01*
X2257702Y716196D01*
X2255955Y715613D01*
X2254645Y714447D01*
X2253772Y712405D01*
X2253553Y710363D01*
X2253772Y708321D01*
X2254645Y706571D01*
X2255955Y705113D01*
X2257702Y704530D01*
X2259230Y705113D01*
X2260540Y706280D01*
G01X2271272Y712405D02*
X2278259D01*
X2277604Y714447D01*
X2276512Y715613D01*
X2274984Y716196D01*
X2273455Y715905D01*
X2272145Y715030D01*
X2271272Y712988D01*
X2270835Y711238D01*
Y709488D01*
X2271272Y707738D01*
X2272364Y705988D01*
X2273674Y704822D01*
X2275202Y704530D01*
X2276730Y705113D01*
X2278259Y706863D01*
G01X1819547Y681546D02*
Y669880D01*
G01Y686213D02*
X1819110Y686505D01*
Y687088D01*
X1819547Y687380D01*
X1819984Y687088D01*
Y686505D01*
X1819547Y686213D01*
G01X1833772Y671921D02*
X1834864Y670755D01*
X1836392Y669880D01*
X1837702D01*
X1839012Y670463D01*
X1839885Y671338D01*
X1840322Y672504D01*
X1840104Y674255D01*
X1839230Y675130D01*
X1835300Y676880D01*
X1834427Y678922D01*
X1834864Y680380D01*
X1835737Y681255D01*
X1837047Y681546D01*
X1838357Y681255D01*
X1839667Y680380D01*
G01X1867025Y669880D02*
Y687380D01*
X1877069Y669880D01*
Y687380D01*
G01X1889547Y669880D02*
X1887800Y670172D01*
X1886272Y671338D01*
X1884962Y673088D01*
X1884088Y675130D01*
X1883652Y677463D01*
Y679797D01*
X1884088Y682130D01*
X1884962Y684172D01*
X1886272Y685921D01*
X1887800Y687088D01*
X1889547Y687380D01*
X1891293Y687088D01*
X1892822Y685921D01*
X1894132Y684172D01*
X1895006Y682130D01*
X1895442Y679797D01*
Y677463D01*
X1895006Y675130D01*
X1894132Y673088D01*
X1892822Y671338D01*
X1891293Y670172D01*
X1889547Y669880D01*
G01X1907047Y687380D02*
Y669880D01*
G01X1902025Y687380D02*
X1912069D01*
G01X1938335Y681546D02*
Y673380D01*
X1939209Y671338D01*
X1940519Y670172D01*
X1942047Y669880D01*
X1943575Y670172D01*
X1944885Y671338D01*
X1945759Y673380D01*
G01Y669880D02*
Y681546D01*
G01X1956272Y671921D02*
X1957364Y670755D01*
X1958892Y669880D01*
X1960202D01*
X1961512Y670463D01*
X1962385Y671338D01*
X1962822Y672504D01*
X1962604Y674255D01*
X1961730Y675130D01*
X1957800Y676880D01*
X1956927Y678922D01*
X1957364Y680380D01*
X1958237Y681255D01*
X1959547Y681546D01*
X1960857Y681255D01*
X1962167Y680380D01*
G01X1973772Y677755D02*
X1980759D01*
X1980104Y679797D01*
X1979012Y680963D01*
X1977484Y681546D01*
X1975955Y681255D01*
X1974645Y680380D01*
X1973772Y678338D01*
X1973335Y676588D01*
Y674838D01*
X1973772Y673088D01*
X1974864Y671338D01*
X1976174Y670172D01*
X1977702Y669880D01*
X1979230Y670463D01*
X1980759Y672213D01*
G01X1998477Y687380D02*
Y669880D01*
G01Y672504D02*
X1997604Y671046D01*
X1996293Y670172D01*
X1994765Y669880D01*
X1993019Y670463D01*
X1991709Y671921D01*
X1990835Y673671D01*
X1990617Y675713D01*
X1990835Y677755D01*
X1991709Y679505D01*
X1993019Y680963D01*
X1994765Y681546D01*
X1996293Y681255D01*
X1997385Y680671D01*
X1998477Y679505D01*
G01X3937Y0D02*
X116260D01*
G01X0Y3937D02*
G03X3937Y0I3937J0D01*
G01X0Y723480D02*
Y3937D01*
G01X416Y725241D02*
G03X0Y723480I3521J-1761D01*
G01X18597Y761603D02*
X416Y725241D01*
G01X22118Y763780D02*
G03X18597Y761603I1J-3937D01*
G01X386149Y763780D02*
X22118D01*
G01X120197Y3937D02*
Y429331D01*
G01X116260Y0D02*
G03X120197Y3937I0J3937D01*
G01X128071D02*
G03X132008Y0I3937J0D01*
G01X128071Y43308D02*
G03X120197I-3937J0D01*
G01X132008Y0D02*
X275709D01*
G01X128071Y3937D02*
Y43308D01*
G01X120197Y74016D02*
G03X128071I3937J0D01*
G01D02*
Y425394D01*
G01X124134Y433268D02*
X283583D01*
G01X124134D02*
G03X120197Y429331I0J-3937D01*
G01X188504Y425394D02*
X128071D01*
G01X152497Y21054D02*
G03I-4291J0D01*
G01X188504Y425394D02*
G03Y433268I0J3937D01*
G01X275709Y0D02*
G03X279646Y3937I0J3937D01*
G01X287520Y43308D02*
G03X279646I-3937J0D01*
G01Y3937D02*
Y43308D01*
G01Y74016D02*
G03X287520I3937J0D01*
G01X279646D02*
Y425394D01*
G01X265438Y405580D02*
G03I-4291J0D01*
G01X287520Y429331D02*
G03X283583Y433268I-3937J0D01*
G01X219213D02*
G03Y425394I0J-3937D01*
G01X279646D02*
X219213D01*
G01X291457Y0D02*
X921260D01*
G01X287520Y3937D02*
G03X291457Y0I3937J0D01*
G01X287520Y429331D02*
Y3937D01*
G01X408268Y188976D02*
Y723480D01*
G01Y188976D02*
G03X412205I1968J0D01*
G01X564173D02*
X412205D01*
G01X416142Y348379D02*
Y196851D01*
G01D02*
X560237D01*
G01X416142Y348379D02*
G03X408268I-3937J0D01*
G01Y379088D02*
G03X416142I3937J0D01*
G01Y688303D02*
Y379088D01*
G01Y688303D02*
G03X408268I-3937J0D01*
G01X389671Y761603D02*
G03X386149Y763780I-3522J-1760D01*
G01X407852Y725241D02*
X389671Y761603D01*
G01X408268Y723480D02*
G03X407852Y725241I-3937J0D01*
G01X524242Y763780D02*
X403757D01*
G01D02*
G03X400235Y758082I0J-3937D01*
G01X408268Y719012D02*
G03X416142I3937J0D01*
G01Y723480D02*
G03X414895Y728763I-11811J1D01*
G01X400235Y758082D02*
X414895Y728763D01*
G01X416142Y723480D02*
Y719012D01*
G01X490789Y356293D02*
G03I-4291J0D01*
G01X564173Y188976D02*
G03X568110I1968J0D01*
G01Y589622D02*
Y188976D01*
G01X560237Y261975D02*
Y196851D01*
G01X568111Y261975D02*
G03X560237I-3937J0D01*
G01Y292684D02*
G03X568111I3937J0D01*
G01X560237Y551040D02*
Y292684D01*
G01X568111Y551040D02*
G03X560237I-3937J0D01*
G01X568526Y591382D02*
G03X568110Y589622I3521J-1761D01*
G01X586707Y627745D02*
X568526Y591382D01*
G01X560237Y581748D02*
G03X568111I3937J0D01*
G01X561484Y594905D02*
G03X560237Y589622I10564J-5282D01*
G01D02*
Y581748D01*
G01X579665Y631267D02*
X561484Y594904D01*
G01X524242Y763780D02*
G03X532116I3937J0D01*
G01X834646D02*
X532116D01*
G01X590228Y629921D02*
G03X586707Y627745I0J-3937D01*
G01X842520Y629921D02*
X590228D01*
G01X590229Y637796D02*
G03X579665Y631268I0J-11812D01*
G01X590229Y637796D02*
X838583D01*
G01X842520Y629921D02*
G03X846457Y633858I0J3937D01*
G01Y759843D02*
Y633858D01*
G01X838583Y637796D02*
Y709449D01*
G01X850394Y763780D02*
G03X846457Y759843I0J-3937D01*
G01X903079Y763780D02*
X850394D01*
G01X812123Y734367D02*
G03I-4292J0D01*
G01X838583Y759843D02*
G03X834646Y763780I-3937J0D01*
G01X838583Y740158D02*
G03X846457I3937J0D01*
G01Y709449D02*
G03X838583I-3937J0D01*
G01Y740158D02*
Y759843D01*
G01X921260Y0D02*
G03X925197Y3937I0J3937D01*
G01D02*
Y723480D01*
G01X906600Y761603D02*
G03X903079Y763780I-3522J-1760D01*
G01X924781Y725241D02*
X906600Y761603D01*
G01X925197Y723480D02*
G03X924781Y725241I-3937J0D01*
G54D12*
G01X127320Y571450D02*
G02X127490Y571041I-408J-410D01*
G01X128451Y572582D02*
G02X129090Y571042I-1539J-1541D01*
G01X126947Y573220D02*
G02X128428Y572605I0J-2091D01*
G01X126947Y571620D02*
G02X127294Y571475I-1J-490D01*
G01X128451Y572582D02*
G02X129090Y571042I-1539J-1541D01*
G01X126947Y573220D02*
G02X128428Y572605I0J-2091D01*
G01X116738Y571620D02*
X126947D01*
G01X116738Y573220D02*
X126947D01*
G01X113236Y575122D02*
G03X116738Y571620I3502J0D01*
G01X114836Y575122D02*
G03X116738Y573220I1902J0D01*
G01X116737Y577023D02*
G03X114836Y575122I0J-1901D01*
G01X116737Y578623D02*
G03X113236Y575122I0J-3501D01*
G01X114836D02*
G03X116738Y573220I1902J0D01*
G01X116737Y577023D02*
G03X114836Y575122I0J-1901D01*
G01X128623Y578623D02*
X116737D01*
G01X128623Y577023D02*
X116737D01*
G01X132158Y577159D02*
G03X128623Y578623I-3535J-3536D01*
G01X131026Y576027D02*
G03X128623Y577023I-2404J-2403D01*
G01X133040Y576277D02*
X132158Y577159D01*
G01X131908Y575145D02*
X131026Y576027D01*
G01X136575Y574813D02*
G02X133040Y576277I0J5000D01*
G01X136575Y573213D02*
G02X131908Y575145I-1J6600D01*
G01X142186Y574813D02*
X136575D01*
G01X142186Y573213D02*
X136575D01*
G01X128451Y572582D02*
G02X129090Y571042I-1539J-1541D01*
G01X127320Y571450D02*
G02X127490Y571041I-408J-410D01*
G01X126947Y571620D02*
G02X127294Y571475I-1J-490D01*
G01X126947Y573220D02*
G02X128428Y572605I0J-2091D01*
G01X127320Y571450D02*
G02X127490Y571041I-408J-410D01*
G01X126947Y571620D02*
G02X127294Y571475I-1J-490D01*
G01X116738Y573220D02*
X126947D01*
G01X116738Y571620D02*
X126947D01*
G01X114836Y575122D02*
G03X116738Y573220I1902J0D01*
G01X113236Y575122D02*
G03X116738Y571620I3502J0D01*
G01X116737Y578623D02*
G03X113236Y575122I0J-3501D01*
G01X116737Y577023D02*
G03X114836Y575122I0J-1901D01*
G01X113236D02*
G03X116738Y571620I3502J0D01*
G01X116737Y578623D02*
G03X113236Y575122I0J-3501D01*
G01X128623Y577023D02*
X116737D01*
G01X128623Y578623D02*
X116737D01*
G01X131026Y576027D02*
G03X128623Y577023I-2404J-2403D01*
G01X132158Y577159D02*
G03X128623Y578623I-3535J-3536D01*
G01X131908Y575145D02*
X131026Y576027D01*
G01X133040Y576277D02*
X132158Y577159D01*
G01X136575Y573213D02*
G02X131908Y575145I-1J6600D01*
G01X136575Y574813D02*
G02X133040Y576277I0J5000D01*
G01X142186Y573213D02*
X136575D01*
G01X142186Y574813D02*
X136575D01*
G01X127320Y571450D02*
G02X127490Y571041I-408J-410D01*
G01X128451Y572582D02*
G02X129090Y571042I-1539J-1541D01*
G01X126947Y573220D02*
G02X128428Y572605I0J-2091D01*
G01X126947Y571620D02*
G02X127294Y571475I-1J-490D01*
G01X128451Y572582D02*
G02X129090Y571042I-1539J-1541D01*
G01X126947Y573220D02*
G02X128428Y572605I0J-2091D01*
G01X116738Y571620D02*
X126947D01*
G01X116738Y573220D02*
X126947D01*
G01X113236Y575122D02*
G03X116738Y571620I3502J0D01*
G01X114836Y575122D02*
G03X116738Y573220I1902J0D01*
G01X116737Y577023D02*
G03X114836Y575122I0J-1901D01*
G01X116737Y578623D02*
G03X113236Y575122I0J-3501D01*
G01X114836D02*
G03X116738Y573220I1902J0D01*
G01X116737Y577023D02*
G03X114836Y575122I0J-1901D01*
G01X128623Y578623D02*
X116737D01*
G01X128623Y577023D02*
X116737D01*
G01X132158Y577159D02*
G03X128623Y578623I-3535J-3536D01*
G01X131026Y576027D02*
G03X128623Y577023I-2404J-2403D01*
G01X133040Y576277D02*
X132158Y577159D01*
G01X131908Y575145D02*
X131026Y576027D01*
G01X136575Y574813D02*
G02X133040Y576277I0J5000D01*
G01X136575Y573213D02*
G02X131908Y575145I-1J6600D01*
G01X142186Y574813D02*
X136575D01*
G01X142186Y573213D02*
X136575D01*
G01X128451Y572582D02*
G02X129090Y571042I-1539J-1541D01*
G01X127320Y571450D02*
G02X127490Y571041I-408J-410D01*
G01X126947Y571620D02*
G02X127294Y571475I-1J-490D01*
G01X126947Y573220D02*
G02X128428Y572605I0J-2091D01*
G01X127320Y571450D02*
G02X127490Y571041I-408J-410D01*
G01X126947Y571620D02*
G02X127294Y571475I-1J-490D01*
G01X116738Y573220D02*
X126947D01*
G01X116738Y571620D02*
X126947D01*
G01X114836Y575122D02*
G03X116738Y573220I1902J0D01*
G01X113236Y575122D02*
G03X116738Y571620I3502J0D01*
G01X116737Y578623D02*
G03X113236Y575122I0J-3501D01*
G01X116737Y577023D02*
G03X114836Y575122I0J-1901D01*
G01X113236D02*
G03X116738Y571620I3502J0D01*
G01X116737Y578623D02*
G03X113236Y575122I0J-3501D01*
G01X128623Y577023D02*
X116737D01*
G01X128623Y578623D02*
X116737D01*
G01X131026Y576027D02*
G03X128623Y577023I-2404J-2403D01*
G01X132158Y577159D02*
G03X128623Y578623I-3535J-3536D01*
G01X131908Y575145D02*
X131026Y576027D01*
G01X133040Y576277D02*
X132158Y577159D01*
G01X136575Y573213D02*
G02X131908Y575145I-1J6600D01*
G01X136575Y574813D02*
G02X133040Y576277I0J5000D01*
G01X142186Y573213D02*
X136575D01*
G01X142186Y574813D02*
X136575D01*
G01X152400Y585714D02*
X153368D01*
G01X152399Y587314D02*
X153368D01*
G01X150050Y586687D02*
G03X152400Y585714I2349J2348D01*
G01X151182Y587818D02*
G03X152399Y587314I1217J1217D01*
G01X149264Y587472D02*
X150050Y586686D01*
G01X150396Y588604D02*
X151182Y587818D01*
G01X147750Y588100D02*
G02X149264Y587472I-1J-2142D01*
G01X147750Y589700D02*
G02X150396Y588604I0J-3742D01*
G01X146724Y588100D02*
X147750D01*
G01X146724Y589700D02*
X147750D01*
G01X149864Y578130D02*
X153632D01*
G01X153631Y576530D02*
X149963D01*
G01X152399Y587314D02*
X153368D01*
G01X152400Y585714D02*
X153368D01*
G01X151182Y587818D02*
G03X152399Y587314I1217J1217D01*
G01X150050Y586687D02*
G03X152400Y585714I2349J2348D01*
G01X150396Y588604D02*
X151182Y587818D01*
G01X149264Y587472D02*
X150050Y586686D01*
G01X147750Y589700D02*
G02X150396Y588604I0J-3742D01*
G01X147750Y588100D02*
G02X149264Y587472I-1J-2142D01*
G01X146724Y589700D02*
X147750D01*
G01X146724Y588100D02*
X147750D01*
G01X153631Y576530D02*
X149963D01*
G01X149864Y578130D02*
X153632D01*
G01X152400Y585714D02*
X153368D01*
G01X152399Y587314D02*
X153368D01*
G01X150050Y586687D02*
G03X152400Y585714I2349J2348D01*
G01X151182Y587818D02*
G03X152399Y587314I1217J1217D01*
G01X149264Y587472D02*
X150050Y586686D01*
G01X150396Y588604D02*
X151182Y587818D01*
G01X147750Y588100D02*
G02X149264Y587472I-1J-2142D01*
G01X147750Y589700D02*
G02X150396Y588604I0J-3742D01*
G01X146724Y588100D02*
X147750D01*
G01X146724Y589700D02*
X147750D01*
G01X149864Y578130D02*
X153632D01*
G01X153631Y576530D02*
X149963D01*
G01X152399Y587314D02*
X153368D01*
G01X152400Y585714D02*
X153368D01*
G01X151182Y587818D02*
G03X152399Y587314I1217J1217D01*
G01X150050Y586687D02*
G03X152400Y585714I2349J2348D01*
G01X150396Y588604D02*
X151182Y587818D01*
G01X149264Y587472D02*
X150050Y586686D01*
G01X147750Y589700D02*
G02X150396Y588604I0J-3742D01*
G01X147750Y588100D02*
G02X149264Y587472I-1J-2142D01*
G01X146724Y589700D02*
X147750D01*
G01X146724Y588100D02*
X147750D01*
G01X153631Y576530D02*
X149963D01*
G01X149864Y578130D02*
X153632D01*
G01X145721Y573349D02*
G03X142186Y574813I-3535J-3536D01*
G01X144589Y572217D02*
G03X142186Y573213I-2404J-2403D01*
G01X149416Y571725D02*
G02X145881Y573189I0J5000D01*
G01X149416Y570125D02*
G02X144749Y572057I-1J6600D01*
G01X153400Y571725D02*
X149416D01*
G01X153400Y570125D02*
X149416D01*
G01X144589Y572217D02*
G03X142186Y573213I-2404J-2403D01*
G01X145721Y573349D02*
G03X142186Y574813I-3535J-3536D01*
G01X149416Y570125D02*
G02X144749Y572057I-1J6600D01*
G01X149416Y571725D02*
G02X145881Y573189I0J5000D01*
G01X153400Y570125D02*
X149416D01*
G01X153400Y571725D02*
X149416D01*
G01X145721Y573349D02*
G03X142186Y574813I-3535J-3536D01*
G01X144589Y572217D02*
G03X142186Y573213I-2404J-2403D01*
G01X149416Y571725D02*
G02X145881Y573189I0J5000D01*
G01X149416Y570125D02*
G02X144749Y572057I-1J6600D01*
G01X153400Y571725D02*
X149416D01*
G01X153400Y570125D02*
X149416D01*
G01X144589Y572217D02*
G03X142186Y573213I-2404J-2403D01*
G01X145721Y573349D02*
G03X142186Y574813I-3535J-3536D01*
G01X149416Y570125D02*
G02X144749Y572057I-1J6600D01*
G01X149416Y571725D02*
G02X145881Y573189I0J5000D01*
G01X153400Y570125D02*
X149416D01*
G01X153400Y571725D02*
X149416D01*
G54D13*
G01X222075Y589900D02*
X219427D01*
G01X222583Y588675D02*
X221352D01*
G01X228844Y596669D02*
X222075Y589900D01*
G01X229352Y595444D02*
X222583Y588675D01*
G01X231109Y596669D02*
X228844D01*
G01X231617Y595444D02*
X229352D01*
G01X235200Y600760D02*
X231109Y596669D01*
G01X236425Y600252D02*
X231617Y595444D01*
G01X235200Y604600D02*
Y600760D01*
G01X236425Y604092D02*
Y600252D01*
G01X238549Y607949D02*
X235200Y604600D01*
G01X239057Y606724D02*
X236425Y604092D01*
G01X252663Y607949D02*
X238549D01*
G01X253171Y606724D02*
X239057D01*
G01X253101Y608387D02*
X252663Y607949D01*
G01X253609Y607162D02*
X253171Y606724D01*
G01X257301Y608387D02*
X253101D01*
G01X257151Y607162D02*
X253609D01*
G01X222583Y588675D02*
X221352D01*
G01X222075Y589900D02*
X219427D01*
G01X229352Y595444D02*
X222583Y588675D01*
G01X228844Y596669D02*
X222075Y589900D01*
G01X231617Y595444D02*
X229352D01*
G01X231109Y596669D02*
X228844D01*
G01X236425Y600252D02*
X231617Y595444D01*
G01X235200Y600760D02*
X231109Y596669D01*
G01X236425Y604092D02*
Y600252D01*
G01X235200Y604600D02*
Y600760D01*
G01X239057Y606724D02*
X236425Y604092D01*
G01X238549Y607949D02*
X235200Y604600D01*
G01X253171Y606724D02*
X239057D01*
G01X252663Y607949D02*
X238549D01*
G01X253609Y607162D02*
X253171Y606724D01*
G01X253101Y608387D02*
X252663Y607949D01*
G01X257151Y607162D02*
X253609D01*
G01X257301Y608387D02*
X253101D01*
G01X252680Y601513D02*
X256276D01*
G01X253188Y600288D02*
X256227D01*
G01X248167Y597000D02*
X252680Y601513D01*
G01X248675Y595775D02*
X253188Y600288D01*
G01X239252Y597000D02*
X248167D01*
G01X239760Y595775D02*
X248675D01*
G01X226314Y584062D02*
X239252Y597000D01*
G01X226822Y582837D02*
X239760Y595775D01*
G01X221843Y584062D02*
X226314D01*
G01X221812Y582837D02*
X226822D01*
G01X253188Y600288D02*
X256227D01*
G01X252680Y601513D02*
X256276D01*
G01X248675Y595775D02*
X253188Y600288D01*
G01X248167Y597000D02*
X252680Y601513D01*
G01X239760Y595775D02*
X248675D01*
G01X239252Y597000D02*
X248167D01*
G01X226822Y582837D02*
X239760Y595775D01*
G01X226314Y584062D02*
X239252Y597000D01*
G01X221812Y582837D02*
X226822D01*
G01X221843Y584062D02*
X226314D01*
G01X222075Y589900D02*
X219427D01*
G01X222583Y588675D02*
X221352D01*
G01X228844Y596669D02*
X222075Y589900D01*
G01X229352Y595444D02*
X222583Y588675D01*
G01X231109Y596669D02*
X228844D01*
G01X231617Y595444D02*
X229352D01*
G01X235200Y600760D02*
X231109Y596669D01*
G01X236425Y600252D02*
X231617Y595444D01*
G01X235200Y604600D02*
Y600760D01*
G01X236425Y604092D02*
Y600252D01*
G01X238549Y607949D02*
X235200Y604600D01*
G01X239057Y606724D02*
X236425Y604092D01*
G01X252663Y607949D02*
X238549D01*
G01X253171Y606724D02*
X239057D01*
G01X253101Y608387D02*
X252663Y607949D01*
G01X253609Y607162D02*
X253171Y606724D01*
G01X257301Y608387D02*
X253101D01*
G01X257151Y607162D02*
X253609D01*
G01X222583Y588675D02*
X221352D01*
G01X222075Y589900D02*
X219427D01*
G01X229352Y595444D02*
X222583Y588675D01*
G01X228844Y596669D02*
X222075Y589900D01*
G01X231617Y595444D02*
X229352D01*
G01X231109Y596669D02*
X228844D01*
G01X236425Y600252D02*
X231617Y595444D01*
G01X235200Y600760D02*
X231109Y596669D01*
G01X236425Y604092D02*
Y600252D01*
G01X235200Y604600D02*
Y600760D01*
G01X239057Y606724D02*
X236425Y604092D01*
G01X238549Y607949D02*
X235200Y604600D01*
G01X253171Y606724D02*
X239057D01*
G01X252663Y607949D02*
X238549D01*
G01X253609Y607162D02*
X253171Y606724D01*
G01X253101Y608387D02*
X252663Y607949D01*
G01X257151Y607162D02*
X253609D01*
G01X257301Y608387D02*
X253101D01*
G01X252680Y601513D02*
X256276D01*
G01X253188Y600288D02*
X256227D01*
G01X248167Y597000D02*
X252680Y601513D01*
G01X248675Y595775D02*
X253188Y600288D01*
G01X239252Y597000D02*
X248167D01*
G01X239760Y595775D02*
X248675D01*
G01X226314Y584062D02*
X239252Y597000D01*
G01X226822Y582837D02*
X239760Y595775D01*
G01X221843Y584062D02*
X226314D01*
G01X221812Y582837D02*
X226822D01*
G01X253188Y600288D02*
X256227D01*
G01X252680Y601513D02*
X256276D01*
G01X248675Y595775D02*
X253188Y600288D01*
G01X248167Y597000D02*
X252680Y601513D01*
G01X239760Y595775D02*
X248675D01*
G01X239252Y597000D02*
X248167D01*
G01X226822Y582837D02*
X239760Y595775D01*
G01X226314Y584062D02*
X239252Y597000D01*
G01X221812Y582837D02*
X226822D01*
G01X221843Y584062D02*
X226314D01*
G01X348138Y69677D02*
X347292D01*
G01X348646Y70902D02*
X347299D01*
G01X351359Y66456D02*
X348138Y69677D01*
G01X351867Y67681D02*
X348646Y70902D01*
G01X371194Y66456D02*
X351359D01*
G01X358155Y67681D02*
X351867D01*
G01X348646Y70902D02*
X347299D01*
G01X348138Y69677D02*
X347292D01*
G01X351867Y67681D02*
X348646Y70902D01*
G01X351359Y66456D02*
X348138Y69677D01*
G01X358155Y67681D02*
X351867D01*
G01X371194Y66456D02*
X351359D01*
G01X371194D02*
X351359D01*
G01X348138Y69677D02*
X347292D01*
G01X348646Y70902D02*
X347299D01*
G01X351359Y66456D02*
X348138Y69677D01*
G01X351867Y67681D02*
X348646Y70902D01*
G01X371194Y66456D02*
X351359D01*
G01X358155Y67681D02*
X351867D01*
G01X348646Y70902D02*
X347299D01*
G01X348138Y69677D02*
X347292D01*
G01X351867Y67681D02*
X348646Y70902D01*
G01X351359Y66456D02*
X348138Y69677D01*
G01X358155Y67681D02*
X351867D01*
G01X371194Y66456D02*
X351359D01*
G01X371194D02*
X351359D01*
G01X301851Y266146D02*
X302751D01*
G01Y267371D02*
X301758D01*
G01X302751D02*
X301758D01*
G01X301851Y266146D02*
X302751D01*
G01X320040Y347954D02*
X325441D01*
G01X320145Y349179D02*
X325442D01*
G01X320145D02*
X325442D01*
G01X320040Y347954D02*
X325441D01*
G01X320169Y335359D02*
X331836D01*
G01X320173Y336584D02*
X331837D01*
G01X320173D02*
X331837D01*
G01X320169Y335359D02*
X331836D01*
G01X320035Y322762D02*
X325436D01*
G01X320140Y323987D02*
X325437D01*
G01X320140D02*
X325437D01*
G01X320035Y322762D02*
X325436D01*
G01X320180Y310222D02*
X331847D01*
G01X320184Y311447D02*
X331848D01*
G01X320184D02*
X331848D01*
G01X320180Y310222D02*
X331847D01*
G01X320035Y297615D02*
X325436D01*
G01X320140Y298840D02*
X325437D01*
G01X320140D02*
X325437D01*
G01X320035Y297615D02*
X325436D01*
G01X319694Y284992D02*
X331361D01*
G01X319698Y286217D02*
X331362D01*
G01X319698D02*
X331362D01*
G01X319694Y284992D02*
X331361D01*
G01X301570Y341730D02*
X302470D01*
G01X301477Y342955D02*
X302470D01*
G01X301477D02*
X302470D01*
G01X301570Y341730D02*
X302470D01*
G01X302461Y329130D02*
X304821D01*
G01X302534Y330355D02*
X304822D01*
G01X302534D02*
X304822D01*
G01X302461Y329130D02*
X304821D01*
G01X301570Y316530D02*
X302470D01*
G01X301477Y317755D02*
X302470D01*
G01X301477D02*
X302470D01*
G01X301570Y316530D02*
X302470D01*
G01X302461Y303930D02*
X304821D01*
G01X302534Y305155D02*
X304822D01*
G01X302534D02*
X304822D01*
G01X302461Y303930D02*
X304821D01*
G01X301570Y291330D02*
X302470D01*
G01X301477Y292555D02*
X302470D01*
G01X301477D02*
X302470D01*
G01X301570Y291330D02*
X302470D01*
G01X302534Y279955D02*
X304822D01*
G01X302461Y278730D02*
X304821D01*
G01X302461D02*
X304821D01*
G01X302534Y279955D02*
X304822D01*
G01X320035Y373156D02*
X325436D01*
G01X320140Y374381D02*
X325437D01*
G01X320140D02*
X325437D01*
G01X320035Y373156D02*
X325436D01*
G01X320169Y360612D02*
X331836D01*
G01X320173Y361837D02*
X331837D01*
G01X320173D02*
X331837D01*
G01X320169Y360612D02*
X331836D01*
G01X301570Y366930D02*
X302470D01*
G01X301477Y368155D02*
X302470D01*
G01X301477D02*
X302470D01*
G01X301570Y366930D02*
X302470D01*
G01X302461Y354330D02*
X304821D01*
G01X302534Y355555D02*
X304822D01*
G01X302534D02*
X304822D01*
G01X302461Y354330D02*
X304821D01*
G01X343689Y624844D02*
X342917D01*
G01X344197Y626069D02*
X346771Y623495D01*
G01X342917Y626069D02*
X344197D01*
G01X345546Y622987D02*
X343689Y624844D01*
G01X344197Y626069D02*
X346771Y623495D01*
G01X345546Y621846D02*
Y622987D01*
G01X346771Y623495D02*
Y622354D01*
G01X348530Y618862D02*
X345546Y621846D01*
G01X346771Y622354D02*
X349038Y620087D01*
G01X349738Y618862D02*
X348530D01*
G01X349038Y620087D02*
X349687D01*
G01X349038D02*
X349687D01*
G01X349738Y618862D02*
X348530D01*
G01X346771Y622354D02*
X349038Y620087D01*
G01X348530Y618862D02*
X345546Y621846D01*
G01X346771Y623495D02*
Y622354D01*
G01X345546Y621846D02*
Y622987D01*
G01X344197Y626069D02*
X346771Y623495D01*
G01X343689Y624844D02*
X342917D01*
G01X345546Y622987D02*
X343689Y624844D01*
G01X342917Y626069D02*
X344197D01*
G01X343689Y624844D02*
X342917D01*
G01X346549Y609040D02*
X350238D01*
G01X346041Y610265D02*
X350212D01*
G01X344163Y606654D02*
X346549Y609040D01*
G01X343655Y607879D02*
X346041Y610265D01*
G01X337642Y606654D02*
X344163D01*
G01X337134Y607879D02*
X343655D01*
G01X336651Y605663D02*
X337642Y606654D01*
G01X335426Y606171D02*
X337134Y607879D01*
G01X336651Y603810D02*
Y605663D01*
G01X335426Y603810D02*
Y606171D01*
G01X346041Y610265D02*
X350212D01*
G01X346549Y609040D02*
X350238D01*
G01X343655Y607879D02*
X346041Y610265D01*
G01X344163Y606654D02*
X346549Y609040D01*
G01X337134Y607879D02*
X343655D01*
G01X337642Y606654D02*
X344163D01*
G01X335426Y606171D02*
X337134Y607879D01*
G01X336651Y605663D02*
X337642Y606654D01*
G01X335426Y603810D02*
Y606171D01*
G01X336651Y603810D02*
Y605663D01*
G01X347718Y615011D02*
X350318D01*
G01X347210Y616236D02*
X350179D01*
G01X346817Y615843D02*
X347210Y616236D01*
G01X347325Y614618D02*
X347718Y615011D01*
G01X346817Y615843D02*
X347210Y616236D01*
G01X342719Y615843D02*
X346817D01*
G01X342805Y614618D02*
X347325D01*
G01X342719Y615843D02*
X346817D01*
G01X347210Y616236D02*
X350179D01*
G01X347718Y615011D02*
X350318D01*
G01X346817Y615843D02*
X347210Y616236D01*
G01X347718Y615011D02*
X350318D01*
G01X347325Y614618D02*
X347718Y615011D01*
G01X342719Y615843D02*
X346817D01*
G01X347325Y614618D02*
X347718Y615011D01*
G01X342805Y614618D02*
X347325D01*
G01X343689Y624844D02*
X342917D01*
G01X344197Y626069D02*
X346771Y623495D01*
G01X342917Y626069D02*
X344197D01*
G01X345546Y622987D02*
X343689Y624844D01*
G01X344197Y626069D02*
X346771Y623495D01*
G01X345546Y621846D02*
Y622987D01*
G01X346771Y623495D02*
Y622354D01*
G01X348530Y618862D02*
X345546Y621846D01*
G01X346771Y622354D02*
X349038Y620087D01*
G01X349738Y618862D02*
X348530D01*
G01X349038Y620087D02*
X349687D01*
G01X349038D02*
X349687D01*
G01X349738Y618862D02*
X348530D01*
G01X346771Y622354D02*
X349038Y620087D01*
G01X348530Y618862D02*
X345546Y621846D01*
G01X346771Y623495D02*
Y622354D01*
G01X345546Y621846D02*
Y622987D01*
G01X344197Y626069D02*
X346771Y623495D01*
G01X343689Y624844D02*
X342917D01*
G01X345546Y622987D02*
X343689Y624844D01*
G01X342917Y626069D02*
X344197D01*
G01X343689Y624844D02*
X342917D01*
G01X346549Y609040D02*
X350238D01*
G01X346041Y610265D02*
X350212D01*
G01X344163Y606654D02*
X346549Y609040D01*
G01X343655Y607879D02*
X346041Y610265D01*
G01X337642Y606654D02*
X344163D01*
G01X337134Y607879D02*
X343655D01*
G01X336651Y605663D02*
X337642Y606654D01*
G01X335426Y606171D02*
X337134Y607879D01*
G01X336651Y603810D02*
Y605663D01*
G01X335426Y603810D02*
Y606171D01*
G01X346041Y610265D02*
X350212D01*
G01X346549Y609040D02*
X350238D01*
G01X343655Y607879D02*
X346041Y610265D01*
G01X344163Y606654D02*
X346549Y609040D01*
G01X337134Y607879D02*
X343655D01*
G01X337642Y606654D02*
X344163D01*
G01X335426Y606171D02*
X337134Y607879D01*
G01X336651Y605663D02*
X337642Y606654D01*
G01X335426Y603810D02*
Y606171D01*
G01X336651Y603810D02*
Y605663D01*
G01X347718Y615011D02*
X350318D01*
G01X347210Y616236D02*
X350179D01*
G01X346817Y615843D02*
X347210Y616236D01*
G01X347325Y614618D02*
X347718Y615011D01*
G01X346817Y615843D02*
X347210Y616236D01*
G01X342719Y615843D02*
X346817D01*
G01X342805Y614618D02*
X347325D01*
G01X342719Y615843D02*
X346817D01*
G01X347210Y616236D02*
X350179D01*
G01X347718Y615011D02*
X350318D01*
G01X346817Y615843D02*
X347210Y616236D01*
G01X347718Y615011D02*
X350318D01*
G01X347325Y614618D02*
X347718Y615011D01*
G01X342719Y615843D02*
X346817D01*
G01X347325Y614618D02*
X347718Y615011D01*
G01X342805Y614618D02*
X347325D01*
G01X387985Y61529D02*
X390023Y63567D01*
G01X387477Y62754D02*
X388798Y64075D01*
G01X384716Y61529D02*
X387985D01*
G01X385224Y62754D02*
X387477D01*
G01X379756Y66489D02*
X384716Y61529D01*
G01X380264Y67714D02*
X385224Y62754D01*
G01X387477D02*
X388798Y64075D01*
G01X387985Y61529D02*
X390023Y63567D01*
G01X385224Y62754D02*
X387477D01*
G01X384716Y61529D02*
X387985D01*
G01X380264Y67714D02*
X385224Y62754D01*
G01X379756Y66489D02*
X384716Y61529D01*
G01X387985D02*
X390023Y63567D01*
G01X387477Y62754D02*
X388798Y64075D01*
G01X384716Y61529D02*
X387985D01*
G01X385224Y62754D02*
X387477D01*
G01X379756Y66489D02*
X384716Y61529D01*
G01X380264Y67714D02*
X385224Y62754D01*
G01X387477D02*
X388798Y64075D01*
G01X387985Y61529D02*
X390023Y63567D01*
G01X385224Y62754D02*
X387477D01*
G01X384716Y61529D02*
X387985D01*
G01X380264Y67714D02*
X385224Y62754D01*
G01X379756Y66489D02*
X384716Y61529D01*
G01X423833Y99368D02*
X431803Y91398D01*
G01X423325Y98143D02*
X431295Y90173D01*
G01X411015Y99368D02*
X423833D01*
G01X410507Y98143D02*
X423325D01*
G01X403165Y107218D02*
X411015Y99368D01*
G01X401940Y106710D02*
X410507Y98143D01*
G01X403165Y154588D02*
Y107218D01*
G01X401940Y154880D02*
Y106710D01*
G01X423325Y98143D02*
X431295Y90173D01*
G01X423833Y99368D02*
X431803Y91398D01*
G01X410507Y98143D02*
X423325D01*
G01X411015Y99368D02*
X423833D01*
G01X401940Y106710D02*
X410507Y98143D01*
G01X403165Y107218D02*
X411015Y99368D01*
G01X401940Y154880D02*
Y106710D01*
G01X403165Y154588D02*
Y107218D01*
G01X423833Y99368D02*
X431803Y91398D01*
G01X423325Y98143D02*
X431295Y90173D01*
G01X411015Y99368D02*
X423833D01*
G01X410507Y98143D02*
X423325D01*
G01X403165Y107218D02*
X411015Y99368D01*
G01X401940Y106710D02*
X410507Y98143D01*
G01X403165Y154588D02*
Y107218D01*
G01X401940Y154880D02*
Y106710D01*
G01X423325Y98143D02*
X431295Y90173D01*
G01X423833Y99368D02*
X431803Y91398D01*
G01X410507Y98143D02*
X423325D01*
G01X411015Y99368D02*
X423833D01*
G01X401940Y106710D02*
X410507Y98143D01*
G01X403165Y107218D02*
X411015Y99368D01*
G01X401940Y154880D02*
Y106710D01*
G01X403165Y154588D02*
Y107218D01*
G01X390220Y79540D02*
Y81768D01*
G01X388995Y79835D02*
Y81768D01*
G01Y79835D02*
Y81768D01*
G01X390220Y79540D02*
Y81768D01*
G01X362905Y67681D02*
X361180D01*
G01X390023Y63567D02*
Y65301D01*
G01X388798Y64075D02*
Y65134D01*
G01X372839Y66489D02*
X379756D01*
G01X372836Y67714D02*
X380264D01*
G01X362905Y67681D02*
X361180D01*
G01X388798Y64075D02*
Y65134D01*
G01X390023Y63567D02*
Y65301D01*
G01X372836Y67714D02*
X380264D01*
G01X372839Y66489D02*
X379756D01*
G01X390220Y79540D02*
Y81768D01*
G01X388995Y79835D02*
Y81768D01*
G01Y79835D02*
Y81768D01*
G01X390220Y79540D02*
Y81768D01*
G01X362905Y67681D02*
X361180D01*
G01X390023Y63567D02*
Y65301D01*
G01X388798Y64075D02*
Y65134D01*
G01X372839Y66489D02*
X379756D01*
G01X372836Y67714D02*
X380264D01*
G01X362905Y67681D02*
X361180D01*
G01X388798Y64075D02*
Y65134D01*
G01X390023Y63567D02*
Y65301D01*
G01X372836Y67714D02*
X380264D01*
G01X372839Y66489D02*
X379756D01*
G01X367443Y630376D02*
Y627496D01*
G01X368668Y629868D02*
Y627619D01*
G01X382961Y645894D02*
X367443Y630376D01*
G01X383469Y644669D02*
X368668Y629868D01*
G01D02*
Y627619D01*
G01X367443Y630376D02*
Y627496D01*
G01X383469Y644669D02*
X368668Y629868D01*
G01X382961Y645894D02*
X367443Y630376D01*
G01D02*
Y627496D01*
G01X368668Y629868D02*
Y627619D01*
G01X382961Y645894D02*
X367443Y630376D01*
G01X383469Y644669D02*
X368668Y629868D01*
G01D02*
Y627619D01*
G01X367443Y630376D02*
Y627496D01*
G01X383469Y644669D02*
X368668Y629868D01*
G01X382961Y645894D02*
X367443Y630376D01*
G01X387083Y645894D02*
X382961D01*
G01X387269Y644669D02*
X383469D01*
G01X387269D02*
X383469D01*
G01X387083Y645894D02*
X382961D01*
G01X387083D02*
X382961D01*
G01X387269Y644669D02*
X383469D01*
G01X387269D02*
X383469D01*
G01X387083Y645894D02*
X382961D01*
G01X452930Y118562D02*
Y174401D01*
G01X454155Y118054D02*
Y174909D01*
G01X451200Y116832D02*
X452930Y118562D01*
G01X452425Y116324D02*
X454155Y118054D01*
G01X451200Y111500D02*
Y116832D01*
G01X452425Y112008D02*
Y116324D01*
G01X456899Y105801D02*
X451200Y111500D01*
G01X457407Y107026D02*
X452425Y112008D01*
G01X461400Y105801D02*
X456899D01*
G01X461908Y107026D02*
X457407D01*
G01X465700Y101501D02*
X461400Y105801D01*
G01X466925Y102009D02*
X461908Y107026D01*
G01X465700Y94514D02*
Y101501D01*
G01X466925Y94006D02*
Y102009D01*
G01X462584Y91398D02*
X465700Y94514D01*
G01X463092Y90173D02*
X466925Y94006D01*
G01X451499Y91398D02*
X462584D01*
G01X431295Y90173D02*
X463092D01*
G01X446849Y91398D02*
X448574D01*
G01X431295Y90173D02*
X463092D01*
G01X442199Y91398D02*
X443924D01*
G01X431295Y90173D02*
X463092D01*
G01X431803Y91398D02*
X439274D01*
G01X431295Y90173D02*
X463092D01*
G01X454155Y118054D02*
Y174909D01*
G01X452930Y118562D02*
Y174401D01*
G01X452425Y116324D02*
X454155Y118054D01*
G01X451200Y116832D02*
X452930Y118562D01*
G01X452425Y112008D02*
Y116324D01*
G01X451200Y111500D02*
Y116832D01*
G01X457407Y107026D02*
X452425Y112008D01*
G01X456899Y105801D02*
X451200Y111500D01*
G01X461908Y107026D02*
X457407D01*
G01X461400Y105801D02*
X456899D01*
G01X466925Y102009D02*
X461908Y107026D01*
G01X465700Y101501D02*
X461400Y105801D01*
G01X466925Y94006D02*
Y102009D01*
G01X465700Y94514D02*
Y101501D01*
G01X463092Y90173D02*
X466925Y94006D01*
G01X462584Y91398D02*
X465700Y94514D01*
G01X431295Y90173D02*
X463092D01*
G01X451499Y91398D02*
X462584D01*
G01X446849D02*
X448574D01*
G01X442199D02*
X443924D01*
G01X431803D02*
X439274D01*
G01X452930Y118562D02*
Y174401D01*
G01X454155Y118054D02*
Y174909D01*
G01X451200Y116832D02*
X452930Y118562D01*
G01X452425Y116324D02*
X454155Y118054D01*
G01X451200Y111500D02*
Y116832D01*
G01X452425Y112008D02*
Y116324D01*
G01X456899Y105801D02*
X451200Y111500D01*
G01X457407Y107026D02*
X452425Y112008D01*
G01X461400Y105801D02*
X456899D01*
G01X461908Y107026D02*
X457407D01*
G01X465700Y101501D02*
X461400Y105801D01*
G01X466925Y102009D02*
X461908Y107026D01*
G01X465700Y94514D02*
Y101501D01*
G01X466925Y94006D02*
Y102009D01*
G01X462584Y91398D02*
X465700Y94514D01*
G01X463092Y90173D02*
X466925Y94006D01*
G01X451499Y91398D02*
X462584D01*
G01X431295Y90173D02*
X463092D01*
G01X446849Y91398D02*
X448574D01*
G01X431295Y90173D02*
X463092D01*
G01X442199Y91398D02*
X443924D01*
G01X431295Y90173D02*
X463092D01*
G01X431803Y91398D02*
X439274D01*
G01X431295Y90173D02*
X463092D01*
G01X454155Y118054D02*
Y174909D01*
G01X452930Y118562D02*
Y174401D01*
G01X452425Y116324D02*
X454155Y118054D01*
G01X451200Y116832D02*
X452930Y118562D01*
G01X452425Y112008D02*
Y116324D01*
G01X451200Y111500D02*
Y116832D01*
G01X457407Y107026D02*
X452425Y112008D01*
G01X456899Y105801D02*
X451200Y111500D01*
G01X461908Y107026D02*
X457407D01*
G01X461400Y105801D02*
X456899D01*
G01X466925Y102009D02*
X461908Y107026D01*
G01X465700Y101501D02*
X461400Y105801D01*
G01X466925Y94006D02*
Y102009D01*
G01X465700Y94514D02*
Y101501D01*
G01X463092Y90173D02*
X466925Y94006D01*
G01X462584Y91398D02*
X465700Y94514D01*
G01X431295Y90173D02*
X463092D01*
G01X451499Y91398D02*
X462584D01*
G01X446849D02*
X448574D01*
G01X442199D02*
X443924D01*
G01X431803D02*
X439274D01*
G01X451958Y175373D02*
X450575D01*
G01X452466Y176598D02*
X450575D01*
G01X454155Y174909D02*
X452466Y176598D01*
G01X452930Y174401D02*
X451958Y175373D01*
G01X454155Y174909D02*
X452466Y176598D01*
G01D02*
X450575D01*
G01X451958Y175373D02*
X450575D01*
G01X454155Y174909D02*
X452466Y176598D01*
G01X451958Y175373D02*
X450575D01*
G01X452930Y174401D02*
X451958Y175373D01*
G01D02*
X450575D01*
G01X452466Y176598D02*
X450575D01*
G01X454155Y174909D02*
X452466Y176598D01*
G01X452930Y174401D02*
X451958Y175373D01*
G01X454155Y174909D02*
X452466Y176598D01*
G01D02*
X450575D01*
G01X451958Y175373D02*
X450575D01*
G01X454155Y174909D02*
X452466Y176598D01*
G01X451958Y175373D02*
X450575D01*
G01X452930Y174401D02*
X451958Y175373D01*
G01X507268Y106153D02*
Y104497D01*
G01X508493Y105645D02*
Y104497D01*
G01X509289Y108174D02*
X507268Y106153D01*
G01X509797Y106949D02*
X508493Y105645D01*
G01X512602Y108174D02*
X509289D01*
G01X512965Y106949D02*
X509797D01*
G01X528881Y118751D02*
X512602Y108174D01*
G01X529657Y117793D02*
X512965Y106949D01*
G01X530380Y120251D02*
X528881Y118751D01*
G01X532107Y120244D02*
X529657Y117793D01*
G01X530881Y120752D02*
X530380Y120251D01*
G01X532107Y120244D02*
X529657Y117793D01*
G01X530882Y169554D02*
Y120752D01*
G01X532107Y169554D02*
Y120244D01*
G01X508493Y105645D02*
Y104497D01*
G01X507268Y106153D02*
Y104497D01*
G01X509797Y106949D02*
X508493Y105645D01*
G01X509289Y108174D02*
X507268Y106153D01*
G01X512965Y106949D02*
X509797D01*
G01X512602Y108174D02*
X509289D01*
G01X529657Y117793D02*
X512965Y106949D01*
G01X528881Y118751D02*
X512602Y108174D01*
G01X532107Y120244D02*
X529657Y117793D01*
G01X530380Y120251D02*
X528881Y118751D01*
G01X530881Y120752D02*
X530380Y120251D01*
G01X532107Y169554D02*
Y120244D01*
G01X530882Y169554D02*
Y120752D01*
G01X507268Y106153D02*
Y104497D01*
G01X508493Y105645D02*
Y104497D01*
G01X509289Y108174D02*
X507268Y106153D01*
G01X509797Y106949D02*
X508493Y105645D01*
G01X512602Y108174D02*
X509289D01*
G01X512965Y106949D02*
X509797D01*
G01X528881Y118751D02*
X512602Y108174D01*
G01X529657Y117793D02*
X512965Y106949D01*
G01X530380Y120251D02*
X528881Y118751D01*
G01X532107Y120244D02*
X529657Y117793D01*
G01X530881Y120752D02*
X530380Y120251D01*
G01X532107Y120244D02*
X529657Y117793D01*
G01X530882Y169554D02*
Y120752D01*
G01X532107Y169554D02*
Y120244D01*
G01X508493Y105645D02*
Y104497D01*
G01X507268Y106153D02*
Y104497D01*
G01X509797Y106949D02*
X508493Y105645D01*
G01X509289Y108174D02*
X507268Y106153D01*
G01X512965Y106949D02*
X509797D01*
G01X512602Y108174D02*
X509289D01*
G01X529657Y117793D02*
X512965Y106949D01*
G01X528881Y118751D02*
X512602Y108174D01*
G01X532107Y120244D02*
X529657Y117793D01*
G01X530380Y120251D02*
X528881Y118751D01*
G01X530881Y120752D02*
X530380Y120251D01*
G01X532107Y169554D02*
Y120244D01*
G01X530882Y169554D02*
Y120752D01*
G01X529788Y170648D02*
G02X530882Y169554I0J-1094D01*
G01X529788Y171873D02*
G02X532107Y169554I0J-2319D01*
G01X528597Y170648D02*
X529788D01*
G01X528596Y171873D02*
X529788D01*
G01D02*
G02X532107Y169554I0J-2319D01*
G01X529788Y170648D02*
G02X530882Y169554I0J-1094D01*
G01X528596Y171873D02*
X529788D01*
G01X528597Y170648D02*
X529788D01*
G01D02*
G02X530882Y169554I0J-1094D01*
G01X529788Y171873D02*
G02X532107Y169554I0J-2319D01*
G01X528597Y170648D02*
X529788D01*
G01X528596Y171873D02*
X529788D01*
G01D02*
G02X532107Y169554I0J-2319D01*
G01X529788Y170648D02*
G02X530882Y169554I0J-1094D01*
G01X528596Y171873D02*
X529788D01*
G01X528597Y170648D02*
X529788D01*
G01X675389Y535874D02*
Y534700D01*
G01X674164Y535366D02*
Y534675D01*
G01X671939Y539324D02*
X675389Y535874D01*
G01X671431Y538099D02*
X674164Y535366D01*
G01X661522Y539324D02*
X671939D01*
G01X661523Y538099D02*
X671431D01*
G01X660527Y539736D02*
G03X661522Y539324I995J995D01*
G01X659660Y538870D02*
G03X661523Y538099I1861J1861D01*
G01X660042Y540221D02*
X660527Y539736D01*
G01X659176Y539353D02*
X659660Y538869D01*
G01X674164Y535366D02*
Y534675D01*
G01X675389Y535874D02*
Y534700D01*
G01X671431Y538099D02*
X674164Y535366D01*
G01X671939Y539324D02*
X675389Y535874D01*
G01X661523Y538099D02*
X671431D01*
G01X661522Y539324D02*
X671939D01*
G01X659660Y538870D02*
G03X661523Y538099I1861J1861D01*
G01X660527Y539736D02*
G03X661522Y539324I995J995D01*
G01X659176Y539353D02*
X659660Y538869D01*
G01X660042Y540221D02*
X660527Y539736D01*
G01X687200Y538012D02*
Y534700D01*
G01X685975Y538520D02*
Y534675D01*
G01X688412Y539224D02*
X687200Y538012D01*
G01X687187Y539732D02*
X685975Y538520D01*
G01X688412Y542760D02*
Y539224D01*
G01X687187Y542251D02*
Y539732D01*
G01X686939Y544233D02*
X688412Y542760D01*
G01X686073Y543365D02*
X687187Y542251D01*
G01X685975Y538520D02*
Y534675D01*
G01X687200Y538012D02*
Y534700D01*
G01X687187Y539732D02*
X685975Y538520D01*
G01X688412Y539224D02*
X687200Y538012D01*
G01X687187Y542251D02*
Y539732D01*
G01X688412Y542760D02*
Y539224D01*
G01X686073Y543365D02*
X687187Y542251D01*
G01X686939Y544233D02*
X688412Y542760D01*
G01X699011Y543801D02*
Y534700D01*
G01X697786Y544309D02*
Y534675D01*
G01X701242Y546032D02*
X699011Y543801D01*
G01X701518Y548041D02*
X697786Y544309D01*
G01X701243Y546032D02*
X701242D01*
G01X701518Y548041D02*
X697786Y544309D01*
G01X702385Y547174D02*
X701243Y546032D01*
G01X701518Y548041D02*
X697786Y544309D01*
G01X702385Y551488D02*
G02Y547174I-2157J-2157D01*
G01X701518Y550621D02*
G02Y548041I-1290J-1290D01*
G01X701574Y552299D02*
X702385Y551488D01*
G01X700708Y551431D02*
X701518Y550621D01*
G01X697786Y544309D02*
Y534675D01*
G01X699011Y543801D02*
Y534700D01*
G01X701518Y548041D02*
X697786Y544309D01*
G01X701242Y546032D02*
X699011Y543801D01*
G01X701243Y546032D02*
X701242D01*
G01X702385Y547174D02*
X701243Y546032D01*
G01X701518Y550621D02*
G02Y548041I-1290J-1290D01*
G01X702385Y551488D02*
G02Y547174I-2157J-2157D01*
G01X700708Y551431D02*
X701518Y550621D01*
G01X701574Y552299D02*
X702385Y551488D01*
G01X710822Y539462D02*
Y534700D01*
G01X709597Y539970D02*
Y534675D01*
G01X714864Y543504D02*
X710822Y539462D01*
G01X714356Y544729D02*
X709597Y539970D01*
G01X716931Y544729D02*
X714356D01*
G01X709597Y539970D02*
Y534675D01*
G01X710822Y539462D02*
Y534700D01*
G01X714356Y544729D02*
X709597Y539970D01*
G01X714864Y543504D02*
X710822Y539462D01*
G01X716931Y544729D02*
X714356D01*
G01X681294Y537643D02*
Y534700D01*
G01X680069Y537134D02*
Y534675D01*
G01X673145Y545792D02*
X681294Y537643D01*
G01X672279Y544924D02*
X680069Y537134D01*
G01D02*
Y534675D01*
G01X681294Y537643D02*
Y534700D01*
G01X672279Y544924D02*
X680069Y537134D01*
G01X673145Y545792D02*
X681294Y537643D01*
G01X693132Y536872D02*
Y534673D01*
G01X691907Y537380D02*
Y534702D01*
G01X693787Y537527D02*
X693132Y536872D01*
G01X692562Y538035D02*
X691907Y537380D01*
G01X693787Y549788D02*
Y537527D01*
G01X692562Y549788D02*
Y538035D01*
G01X691310Y552265D02*
G02X693787Y549788I0J-2477D01*
G01X691310Y551040D02*
G02X692562Y549788I0J-1252D01*
G01X690009Y552265D02*
X691310D01*
G01X690008Y551040D02*
X691310D01*
G01X688923Y552715D02*
G03X690009Y552265I1086J1086D01*
G01X688057Y551848D02*
G03X690008Y551040I1952J1953D01*
G01X688319Y553319D02*
X688923Y552715D01*
G01X687453Y552452D02*
X688056Y551848D01*
G01X691907Y537380D02*
Y534702D01*
G01X693132Y536872D02*
Y534673D01*
G01X692562Y538035D02*
X691907Y537380D01*
G01X693787Y537527D02*
X693132Y536872D01*
G01X692562Y549788D02*
Y538035D01*
G01X693787Y549788D02*
Y537527D01*
G01X691310Y551040D02*
G02X692562Y549788I0J-1252D01*
G01X691310Y552265D02*
G02X693787Y549788I0J-2477D01*
G01X690008Y551040D02*
X691310D01*
G01X690009Y552265D02*
X691310D01*
G01X688057Y551848D02*
G03X690008Y551040I1952J1953D01*
G01X688923Y552715D02*
G03X690009Y552265I1086J1086D01*
G01X687453Y552452D02*
X688056Y551848D01*
G01X688319Y553319D02*
X688923Y552715D01*
G01X704916Y541261D02*
Y534700D01*
G01X703691Y541769D02*
Y534675D01*
G01X710133Y546478D02*
X704916Y541261D01*
G01X710781Y548859D02*
X703691Y541769D01*
G01X711648Y547992D02*
X710134Y546478D01*
G01X710781Y548859D02*
X703691Y541769D01*
G01X711648Y552222D02*
G02Y547992I-2115J-2115D01*
G01X710781Y551355D02*
G02Y548859I-1248J-1248D01*
G01X710803Y553067D02*
X711648Y552222D01*
G01X709937Y552199D02*
X710781Y551355D01*
G01X703691Y541769D02*
Y534675D01*
G01X704916Y541261D02*
Y534700D01*
G01X710781Y548859D02*
X703691Y541769D01*
G01X710133Y546478D02*
X704916Y541261D01*
G01X711648Y547992D02*
X710134Y546478D01*
G01X710781Y551355D02*
G02Y548859I-1248J-1248D01*
G01X711648Y552222D02*
G02Y547992I-2115J-2115D01*
G01X709937Y552199D02*
X710781Y551355D01*
G01X710803Y553067D02*
X711648Y552222D01*
G01X773814Y537520D02*
Y534700D01*
G01X772589Y537012D02*
Y534675D01*
G01X768934Y542400D02*
X773814Y537520D01*
G01X768426Y541175D02*
X772589Y537012D01*
G01X765468Y542400D02*
X768934D01*
G01X764960Y541175D02*
X768426D01*
G01X758384Y549484D02*
X765468Y542400D01*
G01X757518Y548617D02*
X764960Y541175D01*
G01X772589Y537012D02*
Y534675D01*
G01X773814Y537520D02*
Y534700D01*
G01X768426Y541175D02*
X772589Y537012D01*
G01X768934Y542400D02*
X773814Y537520D01*
G01X764960Y541175D02*
X768426D01*
G01X765468Y542400D02*
X768934D01*
G01X757518Y548617D02*
X764960Y541175D01*
G01X758384Y549484D02*
X765468Y542400D01*
G01X785625Y540975D02*
Y534700D01*
G01X784400Y540467D02*
Y534675D01*
G01X782258Y544342D02*
X785625Y540975D01*
G01X781033Y543834D02*
X784400Y540467D01*
G01X782258Y552852D02*
Y544342D01*
G01X781033Y552851D02*
Y543834D01*
G01X781722Y554146D02*
G02X782258Y552852I-1294J-1294D01*
G01X780855Y553280D02*
G02X781033Y552851I-427J-429D01*
G01X780884Y554984D02*
X781722Y554146D01*
G01X780018Y554117D02*
X780855Y553279D01*
G01X784400Y540467D02*
Y534675D01*
G01X785625Y540975D02*
Y534700D01*
G01X781033Y543834D02*
X784400Y540467D01*
G01X782258Y544342D02*
X785625Y540975D01*
G01X781033Y552851D02*
Y543834D01*
G01X782258Y552852D02*
Y544342D01*
G01X780855Y553280D02*
G02X781033Y552851I-427J-429D01*
G01X781722Y554146D02*
G02X782258Y552852I-1294J-1294D01*
G01X780018Y554117D02*
X780855Y553279D01*
G01X780884Y554984D02*
X781722Y554146D01*
G01X722660Y526100D02*
Y527114D01*
G01X721435Y525592D02*
Y527114D01*
G01X722897Y524158D02*
Y525863D01*
G01X721672Y524155D02*
Y525355D01*
G01X721435Y525592D02*
Y527114D01*
G01X722660Y526100D02*
Y527114D01*
G01X721672Y524155D02*
Y525355D01*
G01X722897Y524158D02*
Y525863D01*
G01X716727Y536102D02*
Y534700D01*
G01X715502Y536610D02*
Y534675D01*
G01X719184Y538559D02*
X716727Y536102D01*
G01X718676Y539784D02*
X715502Y536610D01*
G01X723712Y538559D02*
X719184D01*
G01X723204Y539784D02*
X718676D01*
G01X730636Y545483D02*
X723712Y538559D01*
G01X730781Y547361D02*
X723204Y539784D01*
G01X730637Y545483D02*
X730636D01*
G01X730781Y547361D02*
X723204Y539784D01*
G01X731648Y546494D02*
X730637Y545483D01*
G01X730781Y547361D02*
X723204Y539784D01*
G01X731648Y550322D02*
G02Y546494I-1914J-1914D01*
G01X730781Y549455D02*
G02Y547361I-1047J-1047D01*
G01X730803Y551167D02*
X731648Y550322D01*
G01X729937Y550299D02*
X730781Y549455D01*
G01X715502Y536610D02*
Y534675D01*
G01X716727Y536102D02*
Y534700D01*
G01X718676Y539784D02*
X715502Y536610D01*
G01X719184Y538559D02*
X716727Y536102D01*
G01X723204Y539784D02*
X718676D01*
G01X723712Y538559D02*
X719184D01*
G01X730781Y547361D02*
X723204Y539784D01*
G01X730636Y545483D02*
X723712Y538559D01*
G01X730637Y545483D02*
X730636D01*
G01X731648Y546494D02*
X730637Y545483D01*
G01X730781Y549455D02*
G02Y547361I-1047J-1047D01*
G01X731648Y550322D02*
G02Y546494I-1914J-1914D01*
G01X729937Y550299D02*
X730781Y549455D01*
G01X730803Y551167D02*
X731648Y550322D01*
G01X779719Y538914D02*
Y534700D01*
G01X778494Y538406D02*
Y534675D01*
G01X774284Y544348D02*
X779719Y538914D01*
G01X773417Y543482D02*
X778494Y538406D01*
G01X772252Y546380D02*
X774284Y544348D01*
G01X771027Y545872D02*
X773417Y543482D01*
G01X772252Y550890D02*
Y546380D01*
G01X771027Y550889D02*
Y545872D01*
G01X771385Y552983D02*
G02X772252Y550890I-2093J-2093D01*
G01X770518Y552117D02*
G02X771027Y550889I-1226J-1228D01*
G01X770384Y553984D02*
X771385Y552983D01*
G01X769518Y553117D02*
X770518Y552116D01*
G01X778494Y538406D02*
Y534675D01*
G01X779719Y538914D02*
Y534700D01*
G01X773417Y543482D02*
X778494Y538406D01*
G01X774284Y544348D02*
X779719Y538914D01*
G01X771027Y545872D02*
X773417Y543482D01*
G01X772252Y546380D02*
X774284Y544348D01*
G01X771027Y550889D02*
Y545872D01*
G01X772252Y550890D02*
Y546380D01*
G01X770518Y552117D02*
G02X771027Y550889I-1226J-1228D01*
G01X771385Y552983D02*
G02X772252Y550890I-2093J-2093D01*
G01X769518Y553117D02*
X770518Y552116D01*
G01X770384Y553984D02*
X771385Y552983D01*
G01X717440Y543504D02*
X714864D01*
G01X720961Y547025D02*
X717440Y543504D01*
G01X720094Y547892D02*
X716931Y544729D01*
G01X720961Y550064D02*
G02Y547025I-1520J-1520D01*
G01X720094Y549198D02*
G02Y547892I-653J-653D01*
G01X720642Y550384D02*
X720961Y550064D01*
G01X719084Y550209D02*
X720094Y549198D01*
G01X719951Y551075D02*
X720642Y550384D01*
G01X719084Y550209D02*
X720094Y549198D01*
G01X719950Y551077D02*
X719951Y551076D01*
G01X719084Y550209D02*
X720094Y549198D01*
G01X717440Y543504D02*
X714864D01*
G01X720094Y547892D02*
X716931Y544729D01*
G01X720961Y547025D02*
X717440Y543504D01*
G01X720094Y549198D02*
G02Y547892I-653J-653D01*
G01X720961Y550064D02*
G02Y547025I-1520J-1520D01*
G01X719084Y550209D02*
X720094Y549198D01*
G01X720642Y550384D02*
X720961Y550064D01*
G01X719951Y551075D02*
X720642Y550384D01*
G01X719950Y551077D02*
X719951Y551076D01*
G01X722660Y526100D02*
Y527114D01*
G01X721435Y525592D02*
Y527114D01*
G01X722897Y524158D02*
Y525863D01*
G01X721672Y524155D02*
Y525355D01*
G01X721435Y525592D02*
Y527114D01*
G01X722660Y526100D02*
Y527114D01*
G01X721672Y524155D02*
Y525355D01*
G01X722897Y524158D02*
Y525863D01*
G01X797436Y546703D02*
Y534700D01*
G01X796211Y547211D02*
Y534675D01*
G01X801291Y550558D02*
X797436Y546703D01*
G01X800066Y551066D02*
X796211Y547211D01*
G01X801291Y553056D02*
Y550558D01*
G01X800066Y553055D02*
Y551066D01*
G01X800570Y554797D02*
G02X801291Y553056I-1743J-1742D01*
G01X799703Y553931D02*
G02X800066Y553055I-876J-876D01*
G01X799884Y555484D02*
X800570Y554798D01*
G01X799018Y554616D02*
X799703Y553931D01*
G01X796211Y547211D02*
Y534675D01*
G01X797436Y546703D02*
Y534700D01*
G01X800066Y551066D02*
X796211Y547211D01*
G01X801291Y550558D02*
X797436Y546703D01*
G01X800066Y553055D02*
Y551066D01*
G01X801291Y553056D02*
Y550558D01*
G01X799703Y553931D02*
G02X800066Y553055I-876J-876D01*
G01X800570Y554797D02*
G02X801291Y553056I-1743J-1742D01*
G01X799018Y554616D02*
X799703Y553931D01*
G01X799884Y555484D02*
X800570Y554798D01*
G01X809247Y538312D02*
Y534700D01*
G01X808022Y538820D02*
Y534675D01*
G01X809411Y538475D02*
X809247Y538312D01*
G01X815144Y545940D02*
X808022Y538820D01*
G01X816011Y545073D02*
X809415Y538480D01*
G01X815144Y545940D02*
X808022Y538820D01*
G01X816011Y548359D02*
G02Y545073I-1643J-1643D01*
G01X815144Y547492D02*
G02Y545940I-776J-776D01*
G01X815242Y549127D02*
X816011Y548359D01*
G01X814018Y548617D02*
X815144Y547492D01*
G01X814884Y549485D02*
X815242Y549127D01*
G01X814018Y548617D02*
X815144Y547492D01*
G01X808022Y538820D02*
Y534675D01*
G01X809247Y538312D02*
Y534700D01*
G01X815144Y545940D02*
X808022Y538820D01*
G01X809411Y538475D02*
X809247Y538312D01*
G01X816011Y545073D02*
X809415Y538480D01*
G01X815144Y547492D02*
G02Y545940I-776J-776D01*
G01X816011Y548359D02*
G02Y545073I-1643J-1643D01*
G01X814018Y548617D02*
X815144Y547492D01*
G01X815242Y549127D02*
X816011Y548359D01*
G01X814884Y549485D02*
X815242Y549127D01*
G01X821084Y535674D02*
Y534833D01*
G01X819859Y536182D02*
Y534951D01*
G01X824685Y539275D02*
X821084Y535674D01*
G01X824177Y540500D02*
X819859Y536182D01*
G01X826208Y539275D02*
X824685D01*
G01X825700Y540500D02*
X824177D01*
G01X835794Y548861D02*
X826208Y539275D01*
G01X825700Y540500D02*
X824177D01*
G01X833043Y547843D02*
X825700Y540500D01*
G01X834927Y549728D02*
X833043Y547844D01*
G01X839400Y548861D02*
G03X835794I-1803J-1803D01*
G01X840267Y549728D02*
G03X834927I-2670J-2670D01*
G01X840248Y548013D02*
X839400Y548861D01*
G01X841114Y548881D02*
X840267Y549728D01*
G01X819859Y536182D02*
Y534951D01*
G01X821084Y535674D02*
Y534833D01*
G01X824177Y540500D02*
X819859Y536182D01*
G01X824685Y539275D02*
X821084Y535674D01*
G01X825700Y540500D02*
X824177D01*
G01X826208Y539275D02*
X824685D01*
G01X835794Y548861D02*
X826208Y539275D01*
G01X833043Y547843D02*
X825700Y540500D01*
G01X835794Y548861D02*
X826208Y539275D01*
G01X834927Y549728D02*
X833043Y547844D01*
G01X835794Y548861D02*
X826208Y539275D01*
G01X840267Y549728D02*
G03X834927I-2670J-2670D01*
G01X839400Y548861D02*
G03X835794I-1803J-1803D01*
G01X841114Y548881D02*
X840267Y549728D01*
G01X840248Y548013D02*
X839400Y548861D01*
G01X803341Y544679D02*
Y534700D01*
G01X802116Y545188D02*
Y534675D01*
G01X809619Y550957D02*
X803341Y544679D01*
G01X808752Y551824D02*
X802116Y545188D01*
G01X809619Y555249D02*
G02Y550957I-2146J-2146D01*
G01X808752Y554382D02*
G02Y551824I-1279J-1279D01*
G01X808884Y555984D02*
X809619Y555249D01*
G01X808018Y555116D02*
X808752Y554382D01*
G01X802116Y545188D02*
Y534675D01*
G01X803341Y544679D02*
Y534700D01*
G01X808752Y551824D02*
X802116Y545188D01*
G01X809619Y550957D02*
X803341Y544679D01*
G01X808752Y554382D02*
G02Y551824I-1279J-1279D01*
G01X809619Y555249D02*
G02Y550957I-2146J-2146D01*
G01X808018Y555116D02*
X808752Y554382D01*
G01X808884Y555984D02*
X809619Y555249D01*
G01X815152Y537000D02*
Y534700D01*
G01X813927Y537508D02*
Y534675D01*
G01X824403Y546250D02*
X815152Y537000D01*
G01X823895Y547475D02*
X813927Y537508D01*
G01X825252Y546250D02*
X824403D01*
G01X823895Y547475D02*
X813927Y537508D01*
G01X824743Y547475D02*
X823895D01*
G01X828232Y549230D02*
X825252Y546250D01*
G01X827365Y550097D02*
X824743Y547475D01*
G01X828232Y553636D02*
G02Y549230I-2203J-2203D01*
G01X827365Y552769D02*
G02Y550097I-1336J-1336D01*
G01X827384Y554484D02*
X828232Y553636D01*
G01X826518Y553616D02*
X827365Y552769D01*
G01X813927Y537508D02*
Y534675D01*
G01X815152Y537000D02*
Y534700D01*
G01X823895Y547475D02*
X813927Y537508D01*
G01X824403Y546250D02*
X815152Y537000D01*
G01X825252Y546250D02*
X824403D01*
G01X824743Y547475D02*
X823895D01*
G01X825252Y546250D02*
X824403D01*
G01X827365Y550097D02*
X824743Y547475D01*
G01X828232Y549230D02*
X825252Y546250D01*
G01X827365Y552769D02*
G02Y550097I-1336J-1336D01*
G01X828232Y553636D02*
G02Y549230I-2203J-2203D01*
G01X826518Y553616D02*
X827365Y552769D01*
G01X827384Y554484D02*
X828232Y553636D01*
G01X791530Y543470D02*
Y534700D01*
G01X790305Y542962D02*
Y534675D01*
G01X790500Y544500D02*
X791530Y543470D01*
G01X789275Y543992D02*
X790305Y542962D01*
G01X790500Y550420D02*
Y544500D01*
G01X789275Y550929D02*
Y543992D01*
G01X791184Y551104D02*
X790500Y550420D01*
G01X790317Y551971D02*
X789275Y550929D01*
G01X791184Y555184D02*
G02Y551104I-2040J-2040D01*
G01X790317Y554317D02*
G02Y551971I-1173J-1173D01*
G01X790384Y555984D02*
X791184Y555184D01*
G01X789518Y555116D02*
X790317Y554317D01*
G01X790305Y542962D02*
Y534675D01*
G01X791530Y543470D02*
Y534700D01*
G01X789275Y543992D02*
X790305Y542962D01*
G01X790500Y544500D02*
X791530Y543470D01*
G01X789275Y550929D02*
Y543992D01*
G01X790500Y550420D02*
Y544500D01*
G01X790317Y551971D02*
X789275Y550929D01*
G01X791184Y551104D02*
X790500Y550420D01*
G01X790317Y554317D02*
G02Y551971I-1173J-1173D01*
G01X791184Y555184D02*
G02Y551104I-2040J-2040D01*
G01X789518Y555116D02*
X790317Y554317D01*
G01X790384Y555984D02*
X791184Y555184D01*
M02*
